G04 ================== begin FILE IDENTIFICATION RECORD ==================*
G04 Layout Name:  D:/<user>/Wistron_project/16342-2/gbr/16342-2.brd*
G04 Film Name:    L2GND*
G04 File Format:  Gerber RS274X*
G04 File Origin:  Cadence Allegro 16.5-S056*
G04 Origin Date:  Mon Aug 07 11:24:39 2017*
G04 *
G04 Layer:  VIA CLASS/L2GND*
G04 Layer:  PIN/L2GND*
G04 Layer:  ETCH/L2GND*
G04 Layer:  DRAWING FORMAT/LAYER_PCB_STORY*
G04 Layer:  DRAWING FORMAT/LAYER_L2GND*
G04 *
G04 Offset:    (0.00 0.00)*
G04 Mirror:    No*
G04 Mode:      Negative*
G04 Rotation:  0*
G04 FullContactRelief:  No*
G04 UndefLineWidth:     6.00*
G04 ================== end FILE IDENTIFICATION RECORD ====================*
%FSLAX35Y35*MOIN*%
%IR0*IPPOS*OFA0.00000B0.00000*MIA0B0*SFA1.00000B1.00000*%
%AMMACRO11*
4,1,13,.02632,.01218,
.028035,.007425,
.028899,.002443,
.028884,-.002612,
.027991,-.007588,
.02632,-.01218,
.03005,-.01591,
.032356,-.01045,
.033679,-.004673,
.033979,.001247,
.033246,.007128,
.031504,.012793,
.03005,.01591,
.02632,.01218,
0.0*
4,1,13,.01218,-.02632,
.007425,-.028035,
.002443,-.028899,
-.002612,-.028884,
-.007588,-.027991,
-.01218,-.02632,
-.01591,-.03005,
-.01045,-.032356,
-.004673,-.033679,
.001247,-.033979,
.007128,-.033246,
.012793,-.031504,
.01591,-.03005,
.01218,-.02632,
0.0*
4,1,13,-.02632,-.01218,
-.028035,-.007425,
-.028899,-.002443,
-.028884,.002612,
-.027991,.007588,
-.02632,.01218,
-.03005,.01591,
-.032356,.01045,
-.033679,.004673,
-.033979,-.001247,
-.033246,-.007128,
-.031504,-.012793,
-.03005,-.01591,
-.02632,-.01218,
0.0*
4,1,13,-.01218,.02632,
-.007425,.028035,
-.002443,.028899,
.002612,.028884,
.007588,.027991,
.01218,.02632,
.01591,.03005,
.01045,.032356,
.004673,.033679,
-.001247,.033979,
-.007128,.033246,
-.012793,.031504,
-.01591,.03005,
-.01218,.02632,
0.0*
%
%ADD11MACRO11*%
%ADD29O,.072X.123*%
%ADD13C,.03*%
%ADD26C,.032*%
%ADD24C,.06*%
%ADD33C,.043*%
%ADD32C,.062*%
%ADD40C,.063*%
%ADD37C,.072*%
%ADD22C,.036*%
%ADD39C,.091*%
%ADD23C,.028*%
%ADD28C,.056*%
%ADD31C,.076*%
%ADD10C,.068*%
%AMMACRO42*
4,1,15,.00398,.00044,
.003999,.000208,
.004004,-.000025,
.003996,-.000258,
.00398,-.00044,
.00483,-.00129,
.004897,-.001007,
.004947,-.000721,
.004981,-.000432,
.004997,-.000141,
.004997,.000149,
.00498,.00044,
.004946,.000729,
.004895,.001015,
.00483,.00129,
.00398,.00044,
45.*
4,1,15,.00044,-.00398,
.000208,-.003999,
-.000025,-.004004,
-.000258,-.003996,
-.00044,-.00398,
-.00129,-.00483,
-.001007,-.004897,
-.000721,-.004947,
-.000432,-.004981,
-.000141,-.004997,
.000149,-.004997,
.00044,-.00498,
.000729,-.004946,
.001015,-.004895,
.00129,-.00483,
.00044,-.00398,
45.*
4,1,15,-.00398,-.00044,
-.003999,-.000208,
-.004004,.000025,
-.003996,.000258,
-.00398,.00044,
-.00483,.00129,
-.004897,.001007,
-.004947,.000721,
-.004981,.000432,
-.004997,.000141,
-.004997,-.000149,
-.00498,-.00044,
-.004946,-.000729,
-.004895,-.001015,
-.00483,-.00129,
-.00398,-.00044,
45.*
4,1,15,-.00044,.00398,
-.000208,.003999,
.000025,.004004,
.000258,.003996,
.00044,.00398,
.00129,.00483,
.001007,.004897,
.000721,.004947,
.000432,.004981,
.000141,.004997,
-.000149,.004997,
-.00044,.00498,
-.000729,.004946,
-.001015,.004895,
-.00129,.00483,
-.00044,.00398,
45.*
%
%ADD42MACRO42*%
%AMMACRO18*
4,1,15,.00398,.00044,
.003999,.000208,
.004004,-.000025,
.003996,-.000258,
.00398,-.00044,
.00483,-.00129,
.004897,-.001007,
.004947,-.000721,
.004981,-.000432,
.004997,-.000141,
.004997,.000149,
.00498,.00044,
.004946,.000729,
.004895,.001015,
.00483,.00129,
.00398,.00044,
90.*
4,1,15,.00044,-.00398,
.000208,-.003999,
-.000025,-.004004,
-.000258,-.003996,
-.00044,-.00398,
-.00129,-.00483,
-.001007,-.004897,
-.000721,-.004947,
-.000432,-.004981,
-.000141,-.004997,
.000149,-.004997,
.00044,-.00498,
.000729,-.004946,
.001015,-.004895,
.00129,-.00483,
.00044,-.00398,
90.*
4,1,15,-.00398,-.00044,
-.003999,-.000208,
-.004004,.000025,
-.003996,.000258,
-.00398,.00044,
-.00483,.00129,
-.004897,.001007,
-.004947,.000721,
-.004981,.000432,
-.004997,.000141,
-.004997,-.000149,
-.00498,-.00044,
-.004946,-.000729,
-.004895,-.001015,
-.00483,-.00129,
-.00398,-.00044,
90.*
4,1,15,-.00044,.00398,
-.000208,.003999,
.000025,.004004,
.000258,.003996,
.00044,.00398,
.00129,.00483,
.001007,.004897,
.000721,.004947,
.000432,.004981,
.000141,.004997,
-.000149,.004997,
-.00044,.00498,
-.000729,.004946,
-.001015,.004895,
-.00129,.00483,
-.00044,.00398,
90.*
%
%ADD18MACRO18*%
%AMMACRO12*
4,1,15,.00398,.00044,
.003999,.000208,
.004004,-.000025,
.003996,-.000258,
.00398,-.00044,
.00483,-.00129,
.004897,-.001007,
.004947,-.000721,
.004981,-.000432,
.004997,-.000141,
.004997,.000149,
.00498,.00044,
.004946,.000729,
.004895,.001015,
.00483,.00129,
.00398,.00044,
0.0*
4,1,15,.00044,-.00398,
.000208,-.003999,
-.000025,-.004004,
-.000258,-.003996,
-.00044,-.00398,
-.00129,-.00483,
-.001007,-.004897,
-.000721,-.004947,
-.000432,-.004981,
-.000141,-.004997,
.000149,-.004997,
.00044,-.00498,
.000729,-.004946,
.001015,-.004895,
.00129,-.00483,
.00044,-.00398,
0.0*
4,1,15,-.00398,-.00044,
-.003999,-.000208,
-.004004,.000025,
-.003996,.000258,
-.00398,.00044,
-.00483,.00129,
-.004897,.001007,
-.004947,.000721,
-.004981,.000432,
-.004997,.000141,
-.004997,-.000149,
-.00498,-.00044,
-.004946,-.000729,
-.004895,-.001015,
-.00483,-.00129,
-.00398,-.00044,
0.0*
4,1,15,-.00044,.00398,
-.000208,.003999,
.000025,.004004,
.000258,.003996,
.00044,.00398,
.00129,.00483,
.001007,.004897,
.000721,.004947,
.000432,.004981,
.000141,.004997,
-.000149,.004997,
-.00044,.00498,
-.000729,.004946,
-.001015,.004895,
-.00129,.00483,
-.00044,.00398,
0.0*
%
%ADD12MACRO12*%
%ADD36O,.154X.217*%
%ADD35C,.122*%
%ADD14C,.114*%
%ADD34C,.125*%
%ADD25C,.208*%
%ADD20O,.296X.162*%
%ADD30O,.072X.096*%
%ADD21C,.158*%
%ADD15C,.178*%
%ADD19C,.198*%
%AMMACRO38*
4,1,15,.00398,.00044,
.003999,.000208,
.004004,-.000025,
.003996,-.000258,
.00398,-.00044,
.00483,-.00129,
.004897,-.001007,
.004947,-.000721,
.004981,-.000432,
.004997,-.000141,
.004997,.000149,
.00498,.00044,
.004946,.000729,
.004895,.001015,
.00483,.00129,
.00398,.00044,
225.*
4,1,15,.00044,-.00398,
.000208,-.003999,
-.000025,-.004004,
-.000258,-.003996,
-.00044,-.00398,
-.00129,-.00483,
-.001007,-.004897,
-.000721,-.004947,
-.000432,-.004981,
-.000141,-.004997,
.000149,-.004997,
.00044,-.00498,
.000729,-.004946,
.001015,-.004895,
.00129,-.00483,
.00044,-.00398,
225.*
4,1,15,-.00398,-.00044,
-.003999,-.000208,
-.004004,.000025,
-.003996,.000258,
-.00398,.00044,
-.00483,.00129,
-.004897,.001007,
-.004947,.000721,
-.004981,.000432,
-.004997,.000141,
-.004997,-.000149,
-.00498,-.00044,
-.004946,-.000729,
-.004895,-.001015,
-.00483,-.00129,
-.00398,-.00044,
225.*
4,1,15,-.00044,.00398,
-.000208,.003999,
.000025,.004004,
.000258,.003996,
.00044,.00398,
.00129,.00483,
.001007,.004897,
.000721,.004947,
.000432,.004981,
.000141,.004997,
-.000149,.004997,
-.00044,.00498,
-.000729,.004946,
-.001015,.004895,
-.00129,.00483,
-.00044,.00398,
225.*
%
%ADD38MACRO38*%
%AMMACRO17*
4,1,15,.00398,.00044,
.003999,.000208,
.004004,-.000025,
.003996,-.000258,
.00398,-.00044,
.00483,-.00129,
.004897,-.001007,
.004947,-.000721,
.004981,-.000432,
.004997,-.000141,
.004997,.000149,
.00498,.00044,
.004946,.000729,
.004895,.001015,
.00483,.00129,
.00398,.00044,
180.*
4,1,15,.00044,-.00398,
.000208,-.003999,
-.000025,-.004004,
-.000258,-.003996,
-.00044,-.00398,
-.00129,-.00483,
-.001007,-.004897,
-.000721,-.004947,
-.000432,-.004981,
-.000141,-.004997,
.000149,-.004997,
.00044,-.00498,
.000729,-.004946,
.001015,-.004895,
.00129,-.00483,
.00044,-.00398,
180.*
4,1,15,-.00398,-.00044,
-.003999,-.000208,
-.004004,.000025,
-.003996,.000258,
-.00398,.00044,
-.00483,.00129,
-.004897,.001007,
-.004947,.000721,
-.004981,.000432,
-.004997,.000141,
-.004997,-.000149,
-.00498,-.00044,
-.004946,-.000729,
-.004895,-.001015,
-.00483,-.00129,
-.00398,-.00044,
180.*
4,1,15,-.00044,.00398,
-.000208,.003999,
.000025,.004004,
.000258,.003996,
.00044,.00398,
.00129,.00483,
.001007,.004897,
.000721,.004947,
.000432,.004981,
.000141,.004997,
-.000149,.004997,
-.00044,.00498,
-.000729,.004946,
-.001015,.004895,
-.00129,.00483,
-.00044,.00398,
180.*
%
%ADD17MACRO17*%
%AMMACRO16*
4,1,15,.00398,.00044,
.003999,.000208,
.004004,-.000025,
.003996,-.000258,
.00398,-.00044,
.00483,-.00129,
.004897,-.001007,
.004947,-.000721,
.004981,-.000432,
.004997,-.000141,
.004997,.000149,
.00498,.00044,
.004946,.000729,
.004895,.001015,
.00483,.00129,
.00398,.00044,
270.*
4,1,15,.00044,-.00398,
.000208,-.003999,
-.000025,-.004004,
-.000258,-.003996,
-.00044,-.00398,
-.00129,-.00483,
-.001007,-.004897,
-.000721,-.004947,
-.000432,-.004981,
-.000141,-.004997,
.000149,-.004997,
.00044,-.00498,
.000729,-.004946,
.001015,-.004895,
.00129,-.00483,
.00044,-.00398,
270.*
4,1,15,-.00398,-.00044,
-.003999,-.000208,
-.004004,.000025,
-.003996,.000258,
-.00398,.00044,
-.00483,.00129,
-.004897,.001007,
-.004947,.000721,
-.004981,.000432,
-.004997,.000141,
-.004997,-.000149,
-.00498,-.00044,
-.004946,-.000729,
-.004895,-.001015,
-.00483,-.00129,
-.00398,-.00044,
270.*
4,1,15,-.00044,.00398,
-.000208,.003999,
.000025,.004004,
.000258,.003996,
.00044,.00398,
.00129,.00483,
.001007,.004897,
.000721,.004947,
.000432,.004981,
.000141,.004997,
-.000149,.004997,
-.00044,.00498,
-.000729,.004946,
-.001015,.004895,
-.00129,.00483,
-.00044,.00398,
270.*
%
%ADD16MACRO16*%
%AMMACRO41*
4,1,13,.02442,.01028,
.025834,.005883,
.026463,.001308,
.026288,-.003307,
.025315,-.007822,
.02442,-.01028,
.02819,-.01405,
.030201,-.008941,
.031295,-.003561,
.031438,.001927,
.030626,.007357,
.028883,.012564,
.02819,.01405,
.02442,.01028,
0.0*
4,1,13,.01028,-.02442,
.005883,-.025834,
.001308,-.026463,
-.003307,-.026288,
-.007822,-.025315,
-.01028,-.02442,
-.01405,-.02819,
-.008941,-.030201,
-.003561,-.031295,
.001927,-.031438,
.007357,-.030626,
.012564,-.028883,
.01405,-.02819,
.01028,-.02442,
0.0*
4,1,13,-.02442,-.01028,
-.025834,-.005883,
-.026463,-.001308,
-.026288,.003307,
-.025315,.007822,
-.02442,.01028,
-.02819,.01405,
-.030201,.008941,
-.031295,.003561,
-.031438,-.001927,
-.030626,-.007357,
-.028883,-.012564,
-.02819,-.01405,
-.02442,-.01028,
0.0*
4,1,13,-.01028,.02442,
-.005883,.025834,
-.001308,.026463,
.003307,.026288,
.007822,.025315,
.01028,.02442,
.01405,.02819,
.008941,.030201,
.003561,.031295,
-.001927,.031438,
-.007357,.030626,
-.012564,.028883,
-.01405,.02819,
-.01028,.02442,
0.0*
%
%ADD41MACRO41*%
%AMMACRO27*
4,1,19,.02172,.00757,
.022123,.006294,
.022452,.004997,
.022705,.003683,
.02288,.002357,
.022979,.001023,
.022999,-.000315,
.022942,-.001652,
.022807,-.002983,
.022595,-.004304,
.022307,-.005611,
.021943,-.006898,
.02172,-.00757,
.02556,-.01142,
.027155,-.006808,
.027924,-.001989,
.027846,.00289,
.026921,.007681,
.02556,.01142,
.02172,.00757,
0.0*
4,1,19,.00757,-.02172,
.006294,-.022123,
.004997,-.022452,
.003683,-.022705,
.002357,-.02288,
.001023,-.022979,
-.000315,-.022999,
-.001652,-.022942,
-.002983,-.022807,
-.004304,-.022595,
-.005611,-.022307,
-.006898,-.021943,
-.00757,-.02172,
-.01142,-.02556,
-.006808,-.027155,
-.001989,-.027924,
.00289,-.027846,
.007681,-.026921,
.01142,-.02556,
.00757,-.02172,
0.0*
4,1,19,-.02172,-.00757,
-.022123,-.006294,
-.022452,-.004997,
-.022705,-.003683,
-.02288,-.002357,
-.022979,-.001023,
-.022999,.000315,
-.022942,.001652,
-.022807,.002983,
-.022595,.004304,
-.022307,.005611,
-.021943,.006898,
-.02172,.00757,
-.02556,.01142,
-.027155,.006808,
-.027924,.001989,
-.027846,-.00289,
-.026921,-.007681,
-.02556,-.01142,
-.02172,-.00757,
0.0*
4,1,19,-.00757,.02172,
-.006294,.022123,
-.004997,.022452,
-.003683,.022705,
-.002357,.02288,
-.001023,.022979,
.000315,.022999,
.001652,.022942,
.002983,.022807,
.004304,.022595,
.005611,.022307,
.006898,.021943,
.00757,.02172,
.01142,.02556,
.006808,.027155,
.001989,.027924,
-.00289,.027846,
-.007681,.026921,
-.01142,.02556,
-.00757,.02172,
0.0*
%
%ADD27MACRO27*%
%ADD43C,.02*%
%ADD44C,.006*%
%ADD54C,.07204*%
%ADD53C,.05604*%
%ADD55C,.05804*%
%ADD58C,.06804*%
%ADD59C,.08704*%
%ADD46O,.15002X.21302*%
%ADD45O,.15004X.21304*%
%ADD50C,.11004*%
%ADD56C,.12104*%
%ADD62R,.0317X.06104*%
%ADD57C,.11804*%
%ADD51C,.15404*%
%ADD47O,.29202X.15802*%
%ADD63R,.03172X.06104*%
%ADD61R,.08104X.05152*%
%ADD48O,.29204X.15804*%
%ADD60R,.08104X.05154*%
%ADD49C,.37406*%
%ADD52C,.29604*%
G75*
%LPD*%
G75*
G36*
G01X-6000Y-6000D02*
X931197D01*
Y769780D01*
X-6000D01*
Y-6000D01*
G37*
%LPC*%
G75*
G36*
G01X903913Y760260D02*
X922094Y723897D01*
G02X922193Y723480I-834J-418D01*
G01Y3937D01*
G02X921260Y3004I-933J0D01*
G01X291457D01*
G02X290524Y3937I0J933D01*
G01Y429331D01*
G03X283583Y436272I-6941J0D01*
G01X124134D01*
G03X117193Y429331I0J-6941D01*
G01Y3937D01*
G02X116260Y3004I-933J0D01*
G01X3937D01*
G02X3004Y3937I0J933D01*
G01Y723480D01*
G02X3103Y723897I933J-1D01*
G01X21284Y760260D01*
G02X22118Y760776I835J-417D01*
G01X386150D01*
G02X386984Y760260I-1J-933D01*
G01X405165Y723897D01*
G02X405264Y723480I-834J-418D01*
G01Y188976D01*
G03X414199Y185972I4973J0D01*
G01X562179D01*
G03X571114Y188976I3962J3004D01*
G01Y297095D01*
G02X571855Y297305I400J1D01*
G03Y316869I15940J9782D01*
G02X571114Y317079I-341J209D01*
G01Y589621D01*
G02X571213Y590038I933J-1D01*
G01X589394Y626401D01*
G02X590228Y626917I835J-417D01*
G01X842520D01*
G03X849461Y633858I0J6941D01*
G01Y759843D01*
G02X850394Y760776I933J0D01*
G01X903079D01*
G02X903913Y760260I-1J-933D01*
G37*
%LPD*%
G75*
G36*
G01X505170Y47772D02*
X500303Y42905D01*
Y20004D01*
X494992Y14693D01*
X439446D01*
X428500Y25639D01*
Y56858D01*
X430239Y58597D01*
X457136D01*
X458789Y60250D01*
X464587D01*
X465497Y61160D01*
Y67275D01*
X467348Y69126D01*
X499645D01*
X505170Y63601D01*
Y47772D01*
G37*
G36*
G01X805747Y555869D02*
X805750Y555872D01*
X808119Y558240D01*
X808122Y558244D01*
G02X810250Y556128I1115J-1007D01*
G01X807872Y553750D01*
G02X805747Y555869I-1109J1013D01*
G37*
G36*
G01X787247D02*
X787250Y555872D01*
X789619Y558240D01*
X789622Y558244D01*
G02X791750Y556128I1115J-1007D01*
G01X789372Y553750D01*
G02X787247Y555869I-1109J1013D01*
G37*
G36*
G01X796747Y555369D02*
X796750Y555372D01*
X799119Y557740D01*
X799122Y557744D01*
G02X801250Y555628I1115J-1007D01*
G01X798872Y553250D01*
G02X796747Y555369I-1109J1013D01*
G37*
G36*
G01X777747Y554869D02*
X777750Y554872D01*
X780119Y557240D01*
X780122Y557244D01*
G02X782250Y555128I1115J-1007D01*
G01X779872Y552750D01*
G02X777747Y554869I-1109J1013D01*
G37*
G36*
G01X824247Y554369D02*
X824250Y554372D01*
X826619Y556740D01*
X826622Y556744D01*
G02X828750Y554628I1115J-1007D01*
G01X826372Y552250D01*
G02X824247Y554369I-1109J1013D01*
G37*
G36*
G01X767247Y553869D02*
X767250Y553872D01*
X769619Y556240D01*
X769622Y556244D01*
G02X771750Y554128I1115J-1007D01*
G01X769372Y551750D01*
G02X767247Y553869I-1109J1013D01*
G37*
G36*
G01X689685Y553463D02*
X687307Y551085D01*
G02X685182Y553204I-1109J1013D01*
G01X685185Y553207D01*
X687554Y555575D01*
X687557Y555579D01*
G02X689685Y553463I1115J-1007D01*
G37*
G36*
G01X707666Y552952D02*
X707669Y552955D01*
X710038Y555323D01*
X710041Y555327D01*
G02X712169Y553211I1115J-1007D01*
G01X709791Y550833D01*
G02X707666Y552952I-1109J1013D01*
G37*
G36*
G01X698437Y552184D02*
X698440Y552187D01*
X700809Y554555D01*
X700812Y554559D01*
G02X702940Y552443I1115J-1007D01*
G01X700562Y550065D01*
G02X698437Y552184I-1109J1013D01*
G37*
G36*
G01X727666Y551052D02*
X727669Y551055D01*
X730038Y553423D01*
X730041Y553427D01*
G02X732169Y551311I1115J-1007D01*
G01X729791Y548933D01*
G02X727666Y551052I-1109J1013D01*
G37*
G36*
G01X716813Y550962D02*
X716816Y550965D01*
X719185Y553333D01*
X719188Y553337D01*
G02X721316Y551221I1115J-1007D01*
G01X718938Y548843D01*
G02X716813Y550962I-1109J1013D01*
G37*
G36*
G01X811747Y549369D02*
X811750Y549372D01*
X814119Y551740D01*
X814122Y551744D01*
G02X816250Y549628I1115J-1007D01*
G01X813872Y547250D01*
G02X811747Y549369I-1109J1013D01*
G37*
G36*
G01X755247D02*
X755250Y549372D01*
X757619Y551740D01*
X757622Y551744D01*
G02X759750Y549628I1115J-1007D01*
G01X757372Y547250D01*
G02X755247Y549369I-1109J1013D01*
G37*
G36*
G01X838879Y547866D02*
X838882Y547869D01*
X841251Y550237D01*
X841254Y550241D01*
G02X843382Y548125I1115J-1007D01*
G01X841004Y545747D01*
G02X838879Y547866I-1109J1013D01*
G37*
G36*
G01X674511Y545936D02*
X672133Y543558D01*
G02X670008Y545677I-1109J1013D01*
G01X670011Y545680D01*
X672380Y548048D01*
X672383Y548052D01*
G02X674511Y545936I1115J-1007D01*
G37*
G36*
G01X683802Y544118D02*
X683805Y544121D01*
X686174Y546489D01*
X686177Y546493D01*
G02X688305Y544377I1115J-1007D01*
G01X685927Y541999D01*
G02X683802Y544118I-1109J1013D01*
G37*
G36*
G01X661408Y540365D02*
X659030Y537987D01*
G02X656905Y540106I-1109J1013D01*
G01X656908Y540109D01*
X659277Y542477D01*
X659280Y542481D01*
G02X661408Y540365I1115J-1007D01*
G37*
G36*
G01X723958Y522019D02*
X720609D01*
G02Y525019I-73J1500D01*
G01X723963D01*
G02Y522019I73J-1500D01*
G01X723958D01*
G37*
G36*
G01X329684Y375479D02*
Y372054D01*
G02X326680I-1502J-36D01*
G01Y375482D01*
G02X329684I1502J36D01*
G01Y375479D01*
G37*
G36*
G01X305768Y369253D02*
Y365831D01*
X305769Y365828D01*
G02X302765I-1502J-36D01*
G01X302766Y365831D01*
Y369253D01*
X302765Y369256D01*
G02X305769I1502J36D01*
G01X305768Y369253D01*
G37*
G36*
G01X336084Y362935D02*
Y359510D01*
G02X333080I-1502J-36D01*
G01Y362938D01*
G02X336084I1502J36D01*
G01Y362935D01*
G37*
G36*
G01X309068Y356653D02*
Y353231D01*
X309069Y353228D01*
G02X306065I-1502J-36D01*
G01X306066Y353231D01*
Y356653D01*
X306065Y356656D01*
G02X309069I1502J36D01*
G01X309068Y356653D01*
G37*
G36*
G01X329688Y350277D02*
Y346855D01*
X329689Y346852D01*
G02X326685I-1502J-36D01*
G01X326686Y346855D01*
Y350277D01*
X326685Y350280D01*
G02X329689I1502J36D01*
G01X329688Y350277D01*
G37*
G36*
G01X305768Y344053D02*
Y340631D01*
X305769Y340628D01*
G02X302765I-1502J-36D01*
G01X302766Y340631D01*
Y344053D01*
X302765Y344056D01*
G02X305769I1502J36D01*
G01X305768Y344053D01*
G37*
G36*
G01X336084Y337682D02*
Y334257D01*
G02X333080I-1502J-36D01*
G01Y337685D01*
G02X336084I1502J36D01*
G01Y337682D01*
G37*
G36*
G01X309068Y331453D02*
Y328031D01*
X309069Y328028D01*
G02X306065I-1502J-36D01*
G01X306066Y328031D01*
Y331453D01*
X306065Y331456D01*
G02X309069I1502J36D01*
G01X309068Y331453D01*
G37*
G36*
G01X329684Y325085D02*
Y321660D01*
G02X326680I-1502J-36D01*
G01Y325088D01*
G02X329684I1502J36D01*
G01Y325085D01*
G37*
G36*
G01X305768Y318853D02*
Y315431D01*
X305769Y315428D01*
G02X302765I-1502J-36D01*
G01X302766Y315431D01*
Y318853D01*
X302765Y318856D01*
G02X305769I1502J36D01*
G01X305768Y318853D01*
G37*
G36*
G01X336094Y312545D02*
Y309123D01*
X336095Y309120D01*
G02X333091I-1502J-36D01*
G01X333092Y309123D01*
Y312545D01*
X333091Y312548D01*
G02X336095I1502J36D01*
G01X336094Y312545D01*
G37*
G36*
G01X309068Y306253D02*
Y302831D01*
X309069Y302828D01*
G02X306065I-1502J-36D01*
G01X306066Y302831D01*
Y306253D01*
X306065Y306256D01*
G02X309069I1502J36D01*
G01X309068Y306253D01*
G37*
G36*
G01X329684Y299938D02*
Y296513D01*
G02X326680I-1502J-36D01*
G01Y299941D01*
G02X329684I1502J36D01*
G01Y299938D01*
G37*
G36*
G01X305768Y293653D02*
Y290231D01*
X305769Y290228D01*
G02X302765I-1502J-36D01*
G01X302766Y290231D01*
Y293653D01*
X302765Y293656D01*
G02X305769I1502J36D01*
G01X305768Y293653D01*
G37*
G36*
G01X335608Y287315D02*
Y283893D01*
X335609Y283890D01*
G02X332605I-1502J-36D01*
G01X332606Y283893D01*
Y287315D01*
X332605Y287318D01*
G02X335609I1502J36D01*
G01X335608Y287315D01*
G37*
G36*
G01X309068Y281053D02*
Y277631D01*
X309069Y277628D01*
G02X306065I-1502J-36D01*
G01X306066Y277631D01*
Y281053D01*
X306065Y281056D01*
G02X309069I1502J36D01*
G01X309068Y281053D01*
G37*
G36*
G01X306050Y268469D02*
Y265044D01*
G02X303046I-1502J-36D01*
G01Y268472D01*
G02X306050I1502J36D01*
G01Y268469D01*
G37*
G36*
G01X558210Y173420D02*
Y169100D01*
X558219Y169072D01*
G02X554379I-1920J-568D01*
G01X554388Y169100D01*
Y173420D01*
X554379Y173448D01*
G02X558219I1920J568D01*
G01X558210Y173420D01*
G37*
G36*
G01X529864D02*
Y169100D01*
X529873Y169072D01*
G02X526033I-1920J-568D01*
G01X526042Y169100D01*
Y173420D01*
X526033Y173448D01*
G02X529873I1920J568D01*
G01X529864Y173420D01*
G37*
G36*
G01X473172D02*
Y169100D01*
X473180Y169072D01*
G02X469340I-1920J-568D01*
G01X469348Y169100D01*
Y173420D01*
X469340Y173448D01*
G02X473180I1920J568D01*
G01X473172Y173420D01*
G37*
G36*
G01X551124Y149798D02*
Y145478D01*
X551132Y145450D01*
G02X547292I-1920J-568D01*
G01X547300Y145478D01*
Y149798D01*
X547292Y149826D01*
G02X551132I1920J568D01*
G01X551124Y149798D01*
G37*
G36*
G01X536950D02*
Y145478D01*
X536959Y145450D01*
G02X533119I-1920J-568D01*
G01X533128Y145478D01*
Y149798D01*
X533119Y149826D01*
G02X536959I1920J568D01*
G01X536950Y149798D01*
G37*
G36*
G01X522778D02*
Y145478D01*
X522786Y145450D01*
G02X518946I-1920J-568D01*
G01X518954Y145478D01*
Y149798D01*
X518946Y149826D01*
G02X522786I1920J568D01*
G01X522778Y149798D01*
G37*
G36*
G01X508604D02*
Y145478D01*
X508613Y145450D01*
G02X504773I-1920J-568D01*
G01X504782Y145478D01*
Y149798D01*
X504773Y149826D01*
G02X508613I1920J568D01*
G01X508604Y149798D01*
G37*
G36*
G01X466084D02*
Y145478D01*
X466093Y145450D01*
G02X462253I-1920J-568D01*
G01X462262Y145478D01*
Y149798D01*
X462253Y149826D01*
G02X466093I1920J568D01*
G01X466084Y149798D01*
G37*
G36*
G01X451912D02*
Y145478D01*
X451920Y145450D01*
G02X448080I-1920J-568D01*
G01X448088Y145478D01*
Y149798D01*
X448080Y149826D01*
G02X451920I1920J568D01*
G01X451912Y149798D01*
G37*
G36*
G01X437738D02*
Y145478D01*
X437747Y145450D01*
G02X433907I-1920J-568D01*
G01X433916Y145478D01*
Y149798D01*
X433907Y149826D01*
G02X437747I1920J568D01*
G01X437738Y149798D01*
G37*
G36*
G01X423564D02*
Y145478D01*
X423573Y145450D01*
G02X419733I-1920J-568D01*
G01X419742Y145478D01*
Y149798D01*
X419733Y149826D01*
G02X423573I1920J568D01*
G01X423564Y149798D01*
G37*
G36*
G01X558210Y145074D02*
Y140754D01*
X558219Y140726D01*
G02X554379I-1920J-568D01*
G01X554388Y140754D01*
Y145074D01*
X554379Y145102D01*
G02X558219I1920J568D01*
G01X558210Y145074D01*
G37*
G36*
G01X544038D02*
Y140754D01*
X544046Y140726D01*
G02X540206I-1920J-568D01*
G01X540214Y140754D01*
Y145074D01*
X540206Y145102D01*
G02X544046I1920J568D01*
G01X544038Y145074D01*
G37*
G36*
G01X529864D02*
Y140754D01*
X529873Y140726D01*
G02X526033I-1920J-568D01*
G01X526042Y140754D01*
Y145074D01*
X526033Y145102D01*
G02X529873I1920J568D01*
G01X529864Y145074D01*
G37*
G36*
G01X515690D02*
Y140754D01*
X515699Y140726D01*
G02X511859I-1920J-568D01*
G01X511868Y140754D01*
Y145074D01*
X511859Y145102D01*
G02X515699I1920J568D01*
G01X515690Y145074D01*
G37*
G36*
G01X473172D02*
Y140754D01*
X473180Y140726D01*
G02X469340I-1920J-568D01*
G01X469348Y140754D01*
Y145074D01*
X469340Y145102D01*
G02X473180I1920J568D01*
G01X473172Y145074D01*
G37*
G36*
G01X458998D02*
Y140754D01*
X459006Y140726D01*
G02X455166I-1920J-568D01*
G01X455174Y140754D01*
Y145074D01*
X455166Y145102D01*
G02X459006I1920J568D01*
G01X458998Y145074D01*
G37*
G36*
G01X444824D02*
Y140754D01*
X444833Y140726D01*
G02X440993I-1920J-568D01*
G01X441002Y140754D01*
Y145074D01*
X440993Y145102D01*
G02X444833I1920J568D01*
G01X444824Y145074D01*
G37*
G36*
G01X430652D02*
Y140754D01*
X430660Y140726D01*
G02X426820I-1920J-568D01*
G01X426828Y140754D01*
Y145074D01*
X426820Y145102D01*
G02X430660I1920J568D01*
G01X430652Y145074D01*
G37*
G36*
G01X551124Y135625D02*
Y131305D01*
X551132Y131277D01*
G02X547292I-1920J-568D01*
G01X547300Y131305D01*
Y135625D01*
X547292Y135653D01*
G02X551132I1920J568D01*
G01X551124Y135625D01*
G37*
G36*
G01X536950D02*
Y131305D01*
X536959Y131277D01*
G02X533119I-1920J-568D01*
G01X533128Y131305D01*
Y135625D01*
X533119Y135653D01*
G02X536959I1920J568D01*
G01X536950Y135625D01*
G37*
G36*
G01X522778D02*
Y131305D01*
X522786Y131277D01*
G02X518946I-1920J-568D01*
G01X518954Y131305D01*
Y135625D01*
X518946Y135653D01*
G02X522786I1920J568D01*
G01X522778Y135625D01*
G37*
G36*
G01X508604D02*
Y131305D01*
X508613Y131277D01*
G02X504773I-1920J-568D01*
G01X504782Y131305D01*
Y135625D01*
X504773Y135653D01*
G02X508613I1920J568D01*
G01X508604Y135625D01*
G37*
G36*
G01X466084D02*
Y131305D01*
X466093Y131277D01*
G02X462253I-1920J-568D01*
G01X462262Y131305D01*
Y135625D01*
X462253Y135653D01*
G02X466093I1920J568D01*
G01X466084Y135625D01*
G37*
G36*
G01X451912D02*
Y131305D01*
X451920Y131277D01*
G02X448080I-1920J-568D01*
G01X448088Y131305D01*
Y135625D01*
X448080Y135653D01*
G02X451920I1920J568D01*
G01X451912Y135625D01*
G37*
G36*
G01X437738D02*
Y131305D01*
X437747Y131277D01*
G02X433907I-1920J-568D01*
G01X433916Y131305D01*
Y135625D01*
X433907Y135653D01*
G02X437747I1920J568D01*
G01X437738Y135625D01*
G37*
G36*
G01X423564D02*
Y131305D01*
X423573Y131277D01*
G02X419733I-1920J-568D01*
G01X419742Y131305D01*
Y135625D01*
X419733Y135653D01*
G02X423573I1920J568D01*
G01X423564Y135625D01*
G37*
G36*
G01X558210Y130900D02*
Y126581D01*
X558219Y126553D01*
G02X554379I-1920J-568D01*
G01X554388Y126581D01*
Y130900D01*
X554379Y130928D01*
G02X558219I1920J568D01*
G01X558210Y130900D01*
G37*
G36*
G01X544038D02*
Y126581D01*
X544046Y126553D01*
G02X540206I-1920J-568D01*
G01X540214Y126581D01*
Y130900D01*
X540206Y130928D01*
G02X544046I1920J568D01*
G01X544038Y130900D01*
G37*
G36*
G01X529864D02*
Y126581D01*
X529873Y126553D01*
G02X526033I-1920J-568D01*
G01X526042Y126581D01*
Y130900D01*
X526033Y130928D01*
G02X529873I1920J568D01*
G01X529864Y130900D01*
G37*
G36*
G01X515690D02*
Y126581D01*
X515699Y126553D01*
G02X511859I-1920J-568D01*
G01X511868Y126581D01*
Y130900D01*
X511859Y130928D01*
G02X515699I1920J568D01*
G01X515690Y130900D01*
G37*
G36*
G01X473172D02*
Y126581D01*
X473180Y126553D01*
G02X469340I-1920J-568D01*
G01X469348Y126581D01*
Y130900D01*
X469340Y130928D01*
G02X473180I1920J568D01*
G01X473172Y130900D01*
G37*
G36*
G01X458998D02*
Y126581D01*
X459006Y126553D01*
G02X455166I-1920J-568D01*
G01X455174Y126581D01*
Y130900D01*
X455166Y130928D01*
G02X459006I1920J568D01*
G01X458998Y130900D01*
G37*
G36*
G01X444824D02*
Y126581D01*
X444833Y126553D01*
G02X440993I-1920J-568D01*
G01X441002Y126581D01*
Y130900D01*
X440993Y130928D01*
G02X444833I1920J568D01*
G01X444824Y130900D01*
G37*
G36*
G01X430652D02*
Y126581D01*
X430660Y126553D01*
G02X426820I-1920J-568D01*
G01X426828Y126581D01*
Y130900D01*
X426820Y130928D01*
G02X430660I1920J568D01*
G01X430652Y130900D01*
G37*
G36*
G01X509942Y101692D02*
X505815D01*
G02Y104696I-36J1502D01*
G01X509945D01*
G02Y101692I36J-1502D01*
G01X509942D01*
G37*
G54D54*
X305906Y182874D03*
G54D53*
X201801Y684252D03*
X225601D03*
G54D55*
X305906Y388386D03*
G54D58*
X666929Y510236D03*
X765354D03*
G54D59*
X745669D03*
X844094D03*
G54D46*
X706299Y201771D03*
Y83661D03*
G54D45*
X804724Y201772D03*
Y83661D03*
G54D50*
X34652Y111485D03*
X33297Y703990D03*
X899219Y47960D03*
G54D56*
X488838Y137225D03*
G54D62*
X674803Y531004D03*
X698425D03*
X785039D03*
X808661D03*
G54D57*
X488838Y164744D03*
G54D51*
X90157Y413582D03*
X309055Y157677D03*
G54D47*
X309252Y413583D03*
G54D63*
X680708Y531004D03*
X686614D03*
X692520D03*
X704330D03*
X710236D03*
X716142D03*
X773228D03*
X779134D03*
X722048D03*
X790944D03*
X796850D03*
X802756D03*
X814566D03*
X820472D03*
G54D61*
X297146Y266732D03*
X314666Y348622D03*
Y336024D03*
X297146Y329724D03*
Y317126D03*
Y304528D03*
X314666Y298228D03*
Y285630D03*
X297146Y367520D03*
Y354922D03*
X314666Y361220D03*
G54D48*
X89764Y238386D03*
G54D60*
X297146Y279331D03*
Y342323D03*
X314666Y323425D03*
Y310827D03*
X297146Y291929D03*
X314666Y373819D03*
G54D49*
X70866Y98425D03*
Y472441D03*
X49212Y740157D03*
X314961Y472441D03*
X364173Y740157D03*
X405512Y39370D03*
X590551Y472441D03*
X612205Y606299D03*
X875984Y31496D03*
Y472441D03*
Y606299D03*
Y740157D03*
G54D52*
X163189Y669291D03*
%LPC*%
G75*
G36*
G01X494370Y16193D02*
X440068D01*
X430000Y26261D01*
Y56236D01*
X430861Y57097D01*
X457758D01*
X459411Y58750D01*
X465209D01*
X466997Y60538D01*
Y66653D01*
X467970Y67626D01*
X499023D01*
X503670Y62979D01*
Y48394D01*
X498803Y43527D01*
Y20626D01*
X494370Y16193D01*
G37*
%LPD*%
G75*
G54D11*
X56102Y24606D03*
X103346Y34449D03*
G54D29*
X339331Y49803D03*
X360669Y91929D03*
G54D13*
X38500Y56500D03*
X46500Y48500D03*
X28123Y453658D03*
X62276Y550493D03*
X67852Y539219D03*
X67853Y564416D03*
Y554967D03*
Y542368D03*
X64701Y561266D03*
X63456Y555041D03*
X67853Y561266D03*
X64701Y542366D03*
X64151Y521695D03*
X53524Y521269D03*
Y526995D03*
Y532622D03*
X52613Y538242D03*
X52408Y543876D03*
X52603Y549526D03*
X52485Y555153D03*
X53300Y560879D03*
X67853Y577015D03*
X64703Y586463D03*
X64701Y567566D03*
X67853Y570715D03*
X53302Y567317D03*
X58926Y582407D03*
X28667Y634097D03*
X42550Y599224D03*
X56100Y676000D03*
X86268Y58755D03*
X78268Y66755D03*
X121233Y450900D03*
X108500Y475500D03*
X97074Y492891D03*
X112722Y493971D03*
X98400Y473200D03*
X140490Y488605D03*
X132777Y462639D03*
X130787Y479138D03*
X113300Y448564D03*
X118065Y448535D03*
X100600Y490750D03*
X138023Y456188D03*
X140985Y454250D03*
X135262Y475726D03*
X74151Y545516D03*
X86750Y542368D03*
X126337Y554085D03*
X74498Y551757D03*
X130311Y546700D03*
X71002Y539219D03*
X81276Y548766D03*
X119605Y548705D03*
X86750Y539218D03*
X74076Y535966D03*
X83600Y545518D03*
X75508Y542198D03*
X89899Y545518D03*
X127300Y543200D03*
X71002Y542368D03*
X117200Y546300D03*
X89899Y539218D03*
X83600Y539219D03*
X71002Y545518D03*
X86750D03*
X122600Y557480D03*
X71002Y558117D03*
X86750Y554965D03*
Y558115D03*
X83600Y551817D03*
X71002Y564396D03*
Y561266D03*
X83600Y564415D03*
X86750D03*
X75066Y563235D03*
X83600Y561265D03*
X71002Y554967D03*
X86750Y551815D03*
X123300Y530300D03*
X119400Y521700D03*
X133800Y528500D03*
X102601Y507300D03*
X123200Y534600D03*
X78276Y545566D03*
X93744Y542019D03*
X133554Y537374D03*
X71002Y548668D03*
X92600Y535623D03*
X86750Y561265D03*
X89899D03*
X94720Y557158D03*
X92286Y521695D03*
X86659D03*
X81032D03*
X75405D03*
X69778D03*
X97913D03*
X96371Y534124D03*
X125400Y498600D03*
X130607Y569636D03*
X126347Y569556D03*
X117400Y567650D03*
X83600Y573865D03*
X74152Y567565D03*
X86750Y586463D03*
X71002Y567565D03*
X86750Y583313D03*
X74152Y580163D03*
X83601Y580164D03*
X89899Y577014D03*
X74152Y577013D03*
X86750Y577014D03*
X96570Y581730D03*
X118900Y609900D03*
X116400Y626600D03*
X124903Y613900D03*
X124793Y617299D03*
X139500Y611200D03*
X138970Y632277D03*
X74152Y583312D03*
X94011Y597066D03*
X101608Y596523D03*
X93048Y580164D03*
X89899Y567565D03*
X93049Y573864D03*
X93051Y587466D03*
X83600Y567565D03*
X128700Y615500D03*
X138700Y636655D03*
X103098Y620264D03*
X98537Y601094D03*
X102509Y601100D03*
X103109Y608572D03*
X103124Y605153D03*
X103098Y612064D03*
Y624364D03*
X113672Y605134D03*
X113512Y613401D03*
X113426Y609234D03*
X108137Y615870D03*
X113400Y621400D03*
Y617400D03*
X70700Y629000D03*
X133835Y609620D03*
X86028Y696439D03*
X81928Y697539D03*
X106879Y707245D03*
X125376Y701124D03*
X106635Y701465D03*
X94106Y699683D03*
X131300Y650100D03*
X135000Y650000D03*
X89868Y689124D03*
X121300Y651900D03*
X139774Y666686D03*
X119849Y709715D03*
X106355Y710745D03*
X143700Y469000D03*
X188708Y468154D03*
X175115Y463761D03*
X167821Y488301D03*
X208370Y491570D03*
X200260Y465900D03*
X211324Y489886D03*
X167656Y465300D03*
X189700Y463500D03*
X181200Y489451D03*
X155710Y485200D03*
X172300Y478400D03*
X172900Y484101D03*
X169252Y483871D03*
X213159Y460326D03*
X154334Y465100D03*
X149000Y488600D03*
X171537Y464400D03*
X179100Y455800D03*
X201600Y486500D03*
X198200D03*
X190036Y485520D03*
X194411Y485447D03*
X163031Y441700D03*
X193400Y463300D03*
X153489Y481559D03*
X148490Y451286D03*
X144245Y452344D03*
X151877Y450439D03*
X155877D03*
X145000Y488600D03*
X167680Y510640D03*
X166761Y498900D03*
X187500Y523700D03*
X154730Y512704D03*
X158241Y512675D03*
X170700Y513600D03*
X182870Y513832D03*
X212300Y529000D03*
X141980Y508590D03*
X146900Y512500D03*
X185615Y498015D03*
X174900Y499800D03*
X203610Y529397D03*
X179400Y525100D03*
X182964Y510414D03*
X154400Y533500D03*
X187100Y509600D03*
X195200Y513200D03*
X162537Y499000D03*
X160286Y508429D03*
X183750Y524200D03*
X143415Y530143D03*
X171200Y509840D03*
X170800Y499800D03*
X166600Y524100D03*
X144087Y526413D03*
X176900Y496500D03*
X174717Y524010D03*
X178869Y509793D03*
X200650Y497862D03*
X199501Y509275D03*
X191200Y522500D03*
X191300Y525900D03*
X174700Y509600D03*
X207500Y505812D03*
X158000Y499000D03*
X200200Y529200D03*
X156000Y496100D03*
X203696Y533000D03*
X156200Y535800D03*
X188834Y496920D03*
X190929Y512592D03*
X150553Y512500D03*
X148050Y523740D03*
X196800Y497862D03*
X193200Y497000D03*
X174400Y519283D03*
X148409Y575672D03*
X144876Y590854D03*
X148409Y579353D03*
X144876Y587173D03*
X185100Y614300D03*
X179700Y615300D03*
X151800Y615400D03*
X197611Y630698D03*
X193400Y630600D03*
X174799Y630303D03*
X171400Y630200D03*
X199950Y614000D03*
X196100Y614050D03*
X203900Y614100D03*
X144737Y630882D03*
X200100Y633300D03*
X209193Y614249D03*
X162750Y612217D03*
X164400Y609200D03*
X182100Y629800D03*
X178200D03*
X148210Y629830D03*
X141742Y624666D03*
X144263Y609023D03*
X151800Y610300D03*
X188899Y629597D03*
X185500Y629700D03*
X154500Y629600D03*
X195600Y646000D03*
X205827Y695000D03*
X188600Y696800D03*
X159058Y641132D03*
X142572Y640332D03*
X150872D03*
X177100Y640400D03*
X173000D03*
X193400Y639700D03*
X189500D03*
X185300D03*
X181000D03*
X198700D03*
X151949Y691715D03*
X176447Y704925D03*
X162700Y703500D03*
X150849Y710215D03*
X162360Y706888D03*
X168273Y696434D03*
X158994Y694545D03*
X205800Y698400D03*
X210123Y662100D03*
X200000Y664200D03*
X204100Y646500D03*
X199600Y646300D03*
X195500Y696900D03*
X207000Y654400D03*
X185598Y709274D03*
X182200Y709400D03*
X143174Y666586D03*
X162100Y711215D03*
X275276Y494017D03*
X275700Y490300D03*
X275100Y472400D03*
X264800Y467400D03*
X278800Y467500D03*
X277455Y446150D03*
X226475Y480400D03*
X254100Y440800D03*
X257950Y440600D03*
X226500Y477000D03*
X275113Y476513D03*
X266664Y493000D03*
X214808Y463300D03*
X231400Y489800D03*
X237903D03*
X267670Y485870D03*
X271100Y485900D03*
X222995Y443805D03*
X240900Y440900D03*
X236400Y440800D03*
X280600Y448900D03*
X214900Y490000D03*
X231476Y449662D03*
X276591Y483709D03*
X245874Y458478D03*
X242500Y458900D03*
X253400Y453500D03*
X273400Y449700D03*
X249465Y458000D03*
X252626Y469150D03*
X244400Y478600D03*
X244300Y474150D03*
X225532Y450047D03*
X237600Y455500D03*
X233664Y482859D03*
X226607Y444058D03*
X230610Y444055D03*
X272100Y537500D03*
X251346Y554100D03*
X256816Y563982D03*
X262996Y548757D03*
X231450Y563000D03*
X270021Y549394D03*
X283600Y539294D03*
X242700Y548600D03*
X252400Y539600D03*
X271715Y556690D03*
X263400Y531500D03*
X233850Y552201D03*
X234943Y565199D03*
X260513Y564135D03*
X265100Y562300D03*
X227600Y563000D03*
X254494Y529198D03*
X248459Y523892D03*
X269100Y509063D03*
X244850Y540150D03*
X248700Y540000D03*
X228200Y496200D03*
X263600Y540700D03*
X226357Y504514D03*
X257894Y529254D03*
X263600Y535350D03*
X223800Y531600D03*
X236400Y502150D03*
X246508Y532821D03*
X228100Y545500D03*
X227100Y525400D03*
X228800Y542100D03*
X238600Y509900D03*
X228313Y552169D03*
X233100Y509800D03*
X275100D03*
X260900Y553900D03*
X242600Y509800D03*
X233607Y557671D03*
X241154Y536017D03*
X250445Y548551D03*
X255800Y539600D03*
X279200Y531600D03*
X250400Y636976D03*
X215800Y631200D03*
X260705Y598359D03*
X232896Y613795D03*
X231200Y576800D03*
X234700Y581600D03*
X254408Y586483D03*
X255400Y579500D03*
X225900Y630988D03*
X230063Y618667D03*
X274100Y591000D03*
X279745Y608000D03*
X255663Y617763D03*
X276376Y574132D03*
X281636Y588796D03*
X231000Y571900D03*
X242333Y593800D03*
X257346Y599169D03*
X257332Y602569D03*
X258398Y605915D03*
Y609484D03*
X218200Y609500D03*
X262694Y568076D03*
X261300Y571300D03*
X235800Y615100D03*
X233447Y603747D03*
X232300Y600300D03*
X258596Y586356D03*
X259848Y583194D03*
X279214Y591383D03*
X275652Y577455D03*
X237100Y590000D03*
X234087Y618038D03*
X248800Y582000D03*
X273022Y580751D03*
X268200Y578700D03*
X259000Y617000D03*
X234800Y572000D03*
X256007Y575050D03*
X281975Y572963D03*
X279800Y569182D03*
X264200Y574100D03*
X261810Y633980D03*
X264800Y632300D03*
X276783Y588907D03*
X258873Y631373D03*
X215400Y626800D03*
X281510Y583003D03*
X276400Y700650D03*
X254900Y701950D03*
X223013Y645672D03*
X231500Y659100D03*
X255050Y675750D03*
X271240Y698960D03*
X243731Y709100D03*
X272900Y669100D03*
X254600Y685100D03*
X278150Y648363D03*
X284000Y678300D03*
X263800Y648902D03*
X236000Y646100D03*
X272300Y665700D03*
X266398Y679250D03*
X226708Y645869D03*
X239400Y677600D03*
X267045Y695881D03*
X215606Y645300D03*
X277600Y680200D03*
X217638Y695562D03*
X239000Y691000D03*
X276400Y697250D03*
X254700Y708900D03*
X271220Y679910D03*
X255000Y679900D03*
X235042Y656173D03*
X263500Y643212D03*
X243100Y677500D03*
X267100Y699700D03*
X266400Y662200D03*
X254648Y745463D03*
X268520Y719420D03*
X258431Y712169D03*
X268230Y723570D03*
X352000Y109000D03*
X355500D03*
X305651Y199283D03*
X294720Y182200D03*
X320700Y177800D03*
X294720Y178600D03*
Y185600D03*
X307567Y277592D03*
X304548Y268508D03*
Y265008D03*
X335100Y228117D03*
X333882Y273978D03*
Y270578D03*
X335098Y233078D03*
X305782Y230874D03*
X334482Y263778D03*
X333782Y267178D03*
X324000Y222800D03*
X305782Y220674D03*
X305682Y224074D03*
X305782Y217274D03*
X334198Y248824D03*
X305454Y244461D03*
X334282Y252378D03*
X305373Y251101D03*
X306412Y254339D03*
X334260Y255820D03*
X305882Y234274D03*
X305772Y237673D03*
X305781Y241076D03*
X334107Y287354D03*
Y283854D03*
X304267Y344092D03*
Y340592D03*
X307567Y331492D03*
Y327992D03*
X304267Y318892D03*
Y315392D03*
X307567Y306292D03*
Y302792D03*
X304267Y293692D03*
Y290192D03*
X334582Y337721D03*
Y334221D03*
X328187Y350316D03*
Y346816D03*
X328182Y325124D03*
Y321624D03*
X334593Y312584D03*
Y309084D03*
X328182Y299977D03*
Y296477D03*
X307567Y281092D03*
X304267Y369292D03*
Y365792D03*
X307567Y356692D03*
Y353192D03*
X328182Y375518D03*
Y372018D03*
X334582Y362974D03*
Y359474D03*
X336000Y384400D03*
X336230Y377800D03*
X350408Y393708D03*
X348006Y391300D03*
X321859Y388315D03*
X321100Y384874D03*
X346300Y374600D03*
X349100Y379100D03*
X303900Y380574D03*
X348997Y491678D03*
X295700Y428400D03*
X293326Y494174D03*
X344900Y442800D03*
X344688Y493896D03*
X343050Y438900D03*
X339900Y454000D03*
X328313Y435513D03*
X324916Y435360D03*
X321700Y436650D03*
X296254Y546706D03*
X285833Y557629D03*
X302700Y551300D03*
X339062Y521100D03*
X344600Y507600D03*
X341300Y536200D03*
X352921Y536521D03*
X311900Y514900D03*
X287500Y518000D03*
X297850Y524500D03*
X293600Y518400D03*
X288000Y561000D03*
X313300Y518800D03*
X354300Y500245D03*
X288311Y496200D03*
X355600Y506600D03*
X298200Y521100D03*
X301300Y524400D03*
X355600Y513500D03*
X327300Y540100D03*
X341400Y560050D03*
X336881Y530496D03*
X307800Y546700D03*
X341615Y556015D03*
X336953Y534506D03*
X305913Y549643D03*
X331900Y549700D03*
X329050Y552315D03*
X348220Y563836D03*
X344812Y563844D03*
X344755Y497841D03*
X304436Y564081D03*
X341349Y563750D03*
X307350Y561290D03*
X335000Y497000D03*
X332698Y543738D03*
X330200Y535200D03*
X331000Y522100D03*
X302665Y547006D03*
X302506Y543341D03*
X327403Y543499D03*
X336723Y542000D03*
X327800Y514900D03*
X330200Y531800D03*
X323400Y507540D03*
X336800Y506300D03*
X286061Y502378D03*
X293970Y564927D03*
X335000Y500600D03*
X298719Y542538D03*
X293500Y522600D03*
X334811Y551476D03*
X311900Y511500D03*
X309600Y520150D03*
X312300Y540600D03*
X332940Y539287D03*
X333400Y503800D03*
X322900Y530600D03*
X327417Y548344D03*
X290000Y503200D03*
X293800Y503300D03*
X353500Y624500D03*
X353669Y600881D03*
X302300Y582000D03*
X286700Y611911D03*
X340920Y575234D03*
X348000Y612661D03*
X352472Y581000D03*
X325762Y596900D03*
X324900Y581600D03*
X291839Y578193D03*
X293697Y589566D03*
X289070Y573080D03*
X355700Y579317D03*
X341755Y627231D03*
Y623682D03*
X341600Y616962D03*
Y613413D03*
X334264Y602648D03*
X337813D03*
X352716Y594135D03*
X350746Y574837D03*
X293500Y625600D03*
X293600Y629100D03*
X321421Y605265D03*
X323413Y602491D03*
X303000Y586800D03*
X292006Y574797D03*
X315616Y571817D03*
X289800Y569182D03*
X315893Y567721D03*
X341558Y567689D03*
X300043Y603619D03*
X303468Y603647D03*
X352716Y590535D03*
X347784Y587509D03*
X336923Y586749D03*
X347784Y584109D03*
X336923Y583349D03*
X307650Y596000D03*
X285400Y572556D03*
X325761Y592959D03*
X315315Y575204D03*
X317813Y580469D03*
X286400Y569200D03*
X317813Y584969D03*
X325899Y589186D03*
X328356Y678679D03*
X297900Y664800D03*
X290600Y668200D03*
X338301Y673907D03*
X328600Y661100D03*
X343372Y655836D03*
X347013Y656090D03*
X328087Y701587D03*
X327062Y697600D03*
X332200Y643800D03*
X288720Y641455D03*
X289473Y657061D03*
X336000Y662200D03*
X336387Y648987D03*
X317516Y671612D03*
X315000Y674900D03*
X338135Y670511D03*
X342542Y685983D03*
X342645Y682506D03*
X300700Y667000D03*
X330593Y671019D03*
X303741Y654095D03*
X329989Y653920D03*
X291700Y737000D03*
X316465Y716063D03*
X287220Y737920D03*
X334000Y714640D03*
X293075Y726600D03*
X342208Y714950D03*
X337481Y719818D03*
X425765Y56265D03*
X372500Y44500D03*
Y56500D03*
X366500Y124700D03*
X363100Y124600D03*
X387833Y82930D03*
X391382D03*
X372500Y90000D03*
Y78000D03*
X396800Y74800D03*
X365800Y193750D03*
X399900Y152100D03*
X400924Y155896D03*
X404473D03*
X398000Y165400D03*
X398050Y162000D03*
X406400Y150300D03*
X363828Y243944D03*
X381009Y343909D03*
X380799Y347303D03*
X386250Y318250D03*
X380600Y335700D03*
X373700Y329700D03*
X376910Y366078D03*
X359323Y372277D03*
X363699Y382608D03*
X363703Y386008D03*
X363586Y375809D03*
X363701Y379208D03*
X377300Y362700D03*
X361250Y491650D03*
X363942Y450591D03*
X366700Y454800D03*
X359400Y451600D03*
X381276Y469106D03*
X374030Y449526D03*
X372575Y452600D03*
X380200Y457800D03*
X381400Y462000D03*
X387500Y458200D03*
X370800Y475128D03*
X389081Y475224D03*
X387950Y466800D03*
X394700Y481700D03*
X394952Y485300D03*
X378937Y443491D03*
X376697Y446050D03*
X373576Y466300D03*
X373534Y462830D03*
X370900Y471700D03*
X373700Y482700D03*
X378200Y476600D03*
X377691Y451891D03*
X381370Y465500D03*
X388123Y492432D03*
X378840Y448690D03*
X361013Y475128D03*
X372714Y509275D03*
X364000Y525500D03*
X387400Y547500D03*
X384400Y545195D03*
X362666Y504265D03*
X390651Y499000D03*
X387800Y525500D03*
X387700Y521600D03*
X376617Y544817D03*
X397650Y508250D03*
Y536671D03*
X362280Y554590D03*
X397650Y519400D03*
X394880Y548670D03*
X397650Y523900D03*
X393465Y553100D03*
X387700Y517700D03*
X362500Y499970D03*
X365730Y541050D03*
X368900Y505000D03*
X372494Y513020D03*
X383126Y565162D03*
X366490Y564360D03*
X370763Y547900D03*
X370800Y551300D03*
Y554700D03*
X383080Y554897D03*
X384347Y558647D03*
X382922Y561735D03*
X372900Y538700D03*
X396400Y545500D03*
X390769Y495379D03*
X393889Y543207D03*
X367133Y596067D03*
X382380Y612620D03*
X371180Y629236D03*
X386224Y580524D03*
X383411Y577024D03*
X362250Y570875D03*
X364300Y592900D03*
X384500Y616500D03*
X361227Y630300D03*
X378400Y594800D03*
X383313Y621780D03*
X365953Y570753D03*
X382600Y609000D03*
X375700Y580102D03*
X390600Y625500D03*
X366100Y590000D03*
X366500Y586300D03*
X380572Y592095D03*
X396300Y587000D03*
X396400Y583500D03*
X395127Y568056D03*
X395100Y572899D03*
X379100Y703300D03*
X363664Y688950D03*
X384466Y661650D03*
X378832Y659705D03*
X364600Y670800D03*
X388338Y643600D03*
Y647149D03*
X392100Y683900D03*
X392000Y679800D03*
X390500Y665800D03*
Y669200D03*
X396306Y698732D03*
X361914Y680181D03*
X401000Y676500D03*
X371457Y667593D03*
X368060Y667743D03*
X392079Y703434D03*
X396400Y659800D03*
X390355Y690926D03*
X373060Y702960D03*
X398600Y662700D03*
X383600Y711800D03*
X372100Y711700D03*
X478426Y20427D03*
X496394Y30000D03*
X482727Y41870D03*
X486535Y47449D03*
X482397Y52176D03*
X472800Y50000D03*
X469000Y50100D03*
X479040Y47134D03*
X458041Y47341D03*
X476100Y60500D03*
X478700Y62800D03*
X462372Y49179D03*
X486400Y38500D03*
X467016Y20430D03*
X450454Y38147D03*
X486527Y41939D03*
X447233Y48829D03*
X496355Y26000D03*
X496242Y22287D03*
X460300Y57600D03*
X432269Y19980D03*
X486700Y31100D03*
X462874Y95922D03*
X487500Y73400D03*
X485700Y70500D03*
X448000Y80404D03*
X444800Y82404D03*
X478590Y70310D03*
X482200Y70500D03*
X498500Y84200D03*
X471281Y105681D03*
X455766Y114535D03*
X473600Y108300D03*
X457000Y117800D03*
X480538Y112071D03*
X459500Y95500D03*
X441100Y110950D03*
X448996Y117666D03*
X463479Y99412D03*
X515700Y50899D03*
X515785Y55552D03*
X505633Y46932D03*
X502300Y58200D03*
X531050Y46998D03*
X528300Y58648D03*
X515500Y59000D03*
X513500Y62000D03*
X532500Y58600D03*
X543059Y108958D03*
X540800Y111500D03*
X501100Y86800D03*
X538456Y65144D03*
X509981Y103194D03*
X505779D03*
X513300Y83000D03*
X503700Y107600D03*
X599254Y37967D03*
X582447Y50607D03*
X586754Y53967D03*
X577847Y50807D03*
X582797Y31807D03*
X600847Y33907D03*
X588753Y24080D03*
X636647Y64300D03*
X642998Y127863D03*
X642574Y131843D03*
X685907Y30622D03*
X673647Y33107D03*
X680300Y17500D03*
X680000Y23900D03*
X675903Y29541D03*
X668531Y71500D03*
X713200Y387700D03*
X696070Y483486D03*
X712874Y470182D03*
X707391Y484208D03*
X712000Y442100D03*
X711300Y423800D03*
X701183Y453339D03*
X704836D03*
X709700Y480332D03*
X698651Y428165D03*
X669749Y458022D03*
X683000Y447200D03*
X680200Y449500D03*
X705450Y440950D03*
X705700Y493500D03*
X708367Y491000D03*
X708682Y551846D03*
X711156Y554320D03*
X699453Y551078D03*
X701927Y553552D03*
X686198Y552098D03*
X688672Y554572D03*
X684818Y543012D03*
X687292Y545486D03*
X671024Y544571D03*
X673498Y547045D03*
X657921Y539000D03*
X660395Y541474D03*
X653634Y513757D03*
X656846Y521702D03*
X678740Y508760D03*
X777500Y34500D03*
X766200Y22000D03*
X723800Y18600D03*
X718300Y387700D03*
X725200Y442100D03*
X740500Y431000D03*
X723800Y475164D03*
X788263Y554763D03*
X778763Y553763D03*
X781237Y556237D03*
X768263Y552763D03*
X770737Y555237D03*
X756263Y548263D03*
X758737Y550737D03*
X728682Y549946D03*
X731156Y552420D03*
X717829Y549856D03*
X720303Y552330D03*
X720536Y523519D03*
X724036D03*
X759342Y543603D03*
X765935Y537009D03*
X777165Y509835D03*
X845168Y192764D03*
X851137Y199864D03*
X858622Y155614D03*
X854634Y166390D03*
X842511Y164078D03*
X842022Y152174D03*
X857700Y222300D03*
X848868Y219064D03*
X835316Y340914D03*
X846456Y350814D03*
X831650Y422612D03*
X830531Y361589D03*
X794200Y422800D03*
X811300Y395900D03*
X801200Y386700D03*
X796100D03*
X821800Y400500D03*
X821700Y403900D03*
X842820Y382172D03*
X816997Y371022D03*
X847629Y391998D03*
X855320Y414472D03*
X830133Y353930D03*
X842916Y357214D03*
X849420Y407748D03*
X822300Y390000D03*
X811142Y470358D03*
X811668Y433703D03*
X820150Y433900D03*
X794900Y441100D03*
X808100D03*
X807400Y477229D03*
X823710Y469835D03*
X803300Y491600D03*
X806888Y491398D03*
X825263Y553263D03*
X827737Y555737D03*
X812763Y548263D03*
X815237Y550737D03*
X806763Y554763D03*
X809237Y557237D03*
X797763Y554263D03*
X800237Y556737D03*
X790737Y557237D03*
X842369Y549234D03*
X839895Y546760D03*
X867653Y172764D03*
X867851Y163585D03*
X864992Y175435D03*
X864492Y206435D03*
X860868Y219764D03*
X868433Y349134D03*
X864920Y368972D03*
X861420Y367269D03*
X861484Y399069D03*
G54D26*
X265400Y446100D03*
X753800Y535000D03*
G54D24*
X201801Y684252D03*
X225601D03*
G54D33*
X421653Y130709D03*
X428740Y125985D03*
X421653Y136221D03*
X428740Y131496D03*
X421653Y144882D03*
X428740Y140158D03*
X421653Y150394D03*
X428740Y145670D03*
X421653Y159055D03*
X428740Y154331D03*
X421653Y164567D03*
X428740Y159843D03*
X421653Y173229D03*
X428740Y168504D03*
X421653Y178740D03*
X428740Y174016D03*
X435827Y130709D03*
X442913Y125985D03*
X450000Y130709D03*
X457086Y125985D03*
X464173Y130709D03*
X471260Y125985D03*
X435827Y136221D03*
X442913Y131496D03*
X450000Y136221D03*
X457086Y131496D03*
X464173Y136221D03*
X471260Y131496D03*
X435827Y144882D03*
X442913Y140158D03*
X450000Y144882D03*
X457086Y140158D03*
X464173Y144882D03*
X471260Y140158D03*
X435827Y150394D03*
X442913Y145670D03*
X450000Y150394D03*
X457086Y145670D03*
X464173Y150394D03*
X471260Y145670D03*
X435827Y159055D03*
X442913Y154331D03*
X450000Y159055D03*
X457086Y154331D03*
X464173Y159055D03*
X471260Y154331D03*
X435827Y164567D03*
X442913Y159843D03*
X450000Y164567D03*
X457086Y159843D03*
X464173Y164567D03*
X471260Y159843D03*
X435827Y173229D03*
X442913Y168504D03*
X450000Y173229D03*
X457086Y168504D03*
X464173Y173229D03*
X471260Y168504D03*
X435827Y178740D03*
X442913Y174016D03*
X450000Y178740D03*
X457086Y174016D03*
X464173Y178740D03*
X471260Y174016D03*
X506693Y130709D03*
X513779Y125985D03*
X520866Y130709D03*
X527953Y125985D03*
X535039Y130709D03*
X542126Y125985D03*
X549212Y130709D03*
X556299Y125985D03*
X506693Y136221D03*
X513779Y131496D03*
X520866Y136221D03*
X527953Y131496D03*
X535039Y136221D03*
X542126Y131496D03*
X549212Y136221D03*
X556299Y131496D03*
X506693Y144882D03*
X513779Y140158D03*
X520866Y144882D03*
X527953Y140158D03*
X535039Y144882D03*
X542126Y140158D03*
X549212Y144882D03*
X556299Y140158D03*
X506693Y150394D03*
X513779Y145670D03*
X520866Y150394D03*
X527953Y145670D03*
X535039Y150394D03*
X542126Y145670D03*
X549212Y150394D03*
X556299Y145670D03*
X506693Y159055D03*
X513779Y154331D03*
X520866Y159055D03*
X527953Y154331D03*
X535039Y159055D03*
X542126Y154331D03*
X549212Y159055D03*
X556299Y154331D03*
X506693Y164567D03*
X513779Y159843D03*
X520866Y164567D03*
X527953Y159843D03*
X535039Y164567D03*
X542126Y159843D03*
X549212Y164567D03*
X556299Y159843D03*
X506693Y173229D03*
X513779Y168504D03*
X520866Y173229D03*
X527953Y168504D03*
X535039Y173229D03*
X542126Y168504D03*
X549212Y173229D03*
X556299Y168504D03*
X506693Y178740D03*
X513779Y174016D03*
X520866Y178740D03*
X527953Y174016D03*
X535039Y178740D03*
X542126Y174016D03*
X549212Y178740D03*
X556299Y174016D03*
G54D32*
X305906Y388386D03*
G54D22*
X103940Y635460D03*
X76118Y625275D03*
X81118D03*
X76549Y680547D03*
Y675547D03*
X81549Y680547D03*
Y675547D03*
X134223Y691027D03*
X122335Y660582D03*
Y655782D03*
X83125Y719240D03*
Y724040D03*
X155400Y717700D03*
X249200Y733700D03*
Y728700D03*
Y723700D03*
Y718700D03*
Y738500D03*
X334782Y184928D03*
X321182Y202574D03*
Y197774D03*
X305882Y195474D03*
X305382Y190174D03*
X334882Y195478D03*
Y200478D03*
Y190478D03*
X335061Y222578D03*
X335100Y218378D03*
X323492Y214234D03*
X305862Y210014D03*
X322000Y653081D03*
X312400D03*
X317200D03*
X307600D03*
X298700Y674600D03*
X303700D03*
X305559Y720973D03*
X310559D03*
X305559Y725973D03*
X310559D03*
X299500Y725400D03*
X373073Y201889D03*
X491500Y71600D03*
X496500D03*
X491500Y76600D03*
X496500D03*
X516693Y46345D03*
X521493D03*
X516693Y41545D03*
X521493D03*
Y36745D03*
X516693D03*
X521493Y31945D03*
X526530Y43775D03*
X516693Y31945D03*
X567700Y28240D03*
X506500Y76600D03*
X501500D03*
Y71600D03*
X593017Y69796D03*
X588217Y74596D03*
Y69796D03*
X653601Y46761D03*
X658601D03*
X653601Y51761D03*
X658601D03*
X663601Y46761D03*
Y51761D03*
X668601Y46761D03*
Y51761D03*
X649590Y114036D03*
X689875Y464586D03*
X698275Y438305D03*
X683100Y485200D03*
X679832Y494100D03*
Y489100D03*
X679100Y483300D03*
X674900D03*
X674832Y489100D03*
Y494100D03*
X682800Y480700D03*
X736217Y493664D03*
X776658Y489380D03*
X771658D03*
X781658D03*
Y494380D03*
X741217Y493664D03*
X776658Y494380D03*
X771658D03*
X752602Y517850D03*
X736580Y507734D03*
X788015Y507785D03*
X783015D03*
X747602Y517850D03*
X731580Y507734D03*
X716578Y509762D03*
X721590Y511659D03*
X726590D03*
X857965Y273150D03*
X859407Y300314D03*
Y309914D03*
Y305114D03*
Y295314D03*
Y290314D03*
Y285314D03*
X809000Y429400D03*
X840057Y494320D03*
X835057D03*
X836023Y508124D03*
X825161Y507954D03*
X820161D03*
X815161D03*
X805983Y508293D03*
X793015Y507785D03*
X897250Y81510D03*
X902050D03*
Y86310D03*
X897250D03*
Y91110D03*
X902050D03*
X897250Y95910D03*
X902050D03*
X880222Y206781D03*
X875222D03*
X896031Y228468D03*
Y223468D03*
X891031D03*
Y228468D03*
Y238468D03*
X896031D03*
X891031Y233468D03*
X896031D03*
X868376Y271313D03*
X873376D03*
X880122Y216781D03*
X875122D03*
X880222Y211781D03*
X875222D03*
X864207Y300314D03*
Y309914D03*
Y305114D03*
Y295314D03*
Y290314D03*
Y285314D03*
X902091Y369397D03*
X897091D03*
X902091Y374397D03*
X897091D03*
Y379397D03*
X902091D03*
X888548Y392923D03*
X883548D03*
X893548D03*
X888548Y387923D03*
X893548D03*
X883548D03*
G54D37*
X666929Y510236D03*
X765354D03*
G54D40*
X801024Y24409D03*
X821024D03*
G54D23*
X168898Y548819D03*
X165745Y564567D03*
X168895D03*
X159449Y561417D03*
X165748D03*
X172047D03*
X162598Y558268D03*
X168898D03*
X165748Y555118D03*
X159449D03*
X162599Y551970D03*
X194093D03*
X197243D03*
X181497D03*
X175197D03*
X178347D03*
X203542Y555120D03*
X187795D03*
X200393Y551970D03*
X206692Y558269D03*
Y561419D03*
Y564569D03*
X175196Y558269D03*
X190945Y545669D03*
X172047D03*
Y551970D03*
X159449Y545671D03*
X162599Y545669D03*
X165749D03*
X212991Y561419D03*
X184646Y548821D03*
Y545671D03*
X184645Y542519D03*
X206693Y542520D03*
X159449Y542521D03*
X171906Y534661D03*
X212991Y542519D03*
X156299Y545671D03*
X165749Y548819D03*
X175197Y545671D03*
X162599Y542519D03*
X168898D03*
X156299Y542521D03*
X181496Y542520D03*
X159449Y548821D03*
X194094Y542519D03*
X172047Y548819D03*
X168898Y551969D03*
X162599Y548821D03*
X162598Y561417D03*
X168898Y555119D03*
X181497Y548821D03*
X178346Y545670D03*
X181497Y545671D03*
X162595Y564567D03*
X203542Y551970D03*
X181497Y555120D03*
X178346Y555119D03*
X187885Y552058D03*
X197245Y555118D03*
X159412Y552006D03*
X165748Y551968D03*
X178347Y564569D03*
X203543Y561418D03*
Y564568D03*
X172047D03*
X200393Y548819D03*
X209842Y545669D03*
Y564567D03*
Y558268D03*
X212992Y551969D03*
Y548819D03*
X209842Y561417D03*
X212992Y564567D03*
X200393Y545669D03*
X206692Y545671D03*
X209842Y548819D03*
X212992Y545669D03*
X165777Y542555D03*
X209842Y555119D03*
Y551969D03*
X206692Y548820D03*
X206693Y551969D03*
X194094Y545669D03*
Y548820D03*
X175197Y548821D03*
X168898Y545669D03*
X153150Y539371D03*
X153149Y542521D03*
X197244Y545669D03*
Y542519D03*
X156300Y539371D03*
X197243Y589900D03*
X194094Y602362D03*
X206692Y596063D03*
X203450Y592912D03*
X194093Y596063D03*
X172020Y577050D03*
X212991Y567718D03*
X209841Y574016D03*
X206692D03*
X168898Y567717D03*
X159449Y570866D03*
X168898Y583464D03*
Y577165D03*
X159449Y586614D03*
X162598Y580315D03*
Y586614D03*
X165748D03*
X168898D03*
X159449Y577165D03*
X156299D03*
X168898Y580315D03*
X159449D03*
X162598Y577165D03*
X165748Y580315D03*
X162598Y583464D03*
X165748Y570866D03*
Y567717D03*
X162598D03*
X172047Y570867D03*
X194094Y577166D03*
X203543Y574017D03*
X178347Y589764D03*
X181497D03*
X194093Y586614D03*
X209841Y596063D03*
X206692Y583465D03*
Y567600D03*
X212992Y580315D03*
X212991Y577165D03*
X209842Y567717D03*
X212991Y574016D03*
X190945Y599213D03*
X190944Y596063D03*
X187796Y599212D03*
X181586Y599123D03*
X212991Y583465D03*
X209841Y577165D03*
X159448Y596063D03*
X190944Y602362D03*
X203543D03*
X203542Y596063D03*
X194094Y599213D03*
X168898Y596063D03*
X212992Y602363D03*
X212991Y599212D03*
X206692Y589763D03*
X168898Y592913D03*
X162598Y596063D03*
X194093Y589764D03*
Y592913D03*
X206692Y586614D03*
X209842Y586613D03*
X212992Y589764D03*
X209841Y592913D03*
X162598Y570866D03*
X178347Y574018D03*
X203542Y580315D03*
Y586614D03*
X190944D03*
X178346Y586615D03*
X181497Y586614D03*
X178344Y577166D03*
X203542Y577165D03*
X178347Y570769D03*
X203501Y571005D03*
X175298Y577266D03*
X172047Y567717D03*
X178346Y596064D03*
X178347Y599213D03*
X165748D03*
X168898D03*
X162598D03*
X159448D03*
X172048Y596063D03*
X190944Y592913D03*
Y589764D03*
X200393Y586614D03*
X197165Y586540D03*
X212993Y592912D03*
X209842Y589763D03*
X206692Y580315D03*
X209841D03*
X181500Y595900D03*
X200393Y592912D03*
X209841Y599212D03*
X200393D03*
X159448Y589764D03*
Y592913D03*
X162598Y589764D03*
X165748D03*
Y596063D03*
Y592913D03*
X175197D03*
X172048D03*
X181530Y592765D03*
X175197Y596063D03*
Y599213D03*
X172048D03*
X216141Y564569D03*
Y561419D03*
X219291Y542519D03*
X216141D03*
X216142Y548820D03*
X216141Y555120D03*
Y558269D03*
X222441Y548820D03*
X219291D03*
X216141Y551970D03*
X216142Y545669D03*
X216141Y580315D03*
Y577165D03*
Y583465D03*
Y586614D03*
Y567718D03*
X219293Y567717D03*
X216141Y574016D03*
Y599212D03*
Y589762D03*
X230600Y608100D03*
G54D39*
X745669Y510236D03*
X844094D03*
G54D28*
X353543Y62913D03*
Y55039D03*
X346457Y66850D03*
Y74724D03*
Y84567D03*
X353543Y86535D03*
Y78661D03*
Y70787D03*
G54D31*
X305906Y182874D03*
G54D10*
X61024Y34449D03*
X33464D03*
X38386Y24606D03*
X108268Y44292D03*
X80708D03*
X85630Y34449D03*
G54D18*
X67853Y573865D03*
X99337Y683756D03*
Y678756D03*
Y673756D03*
X95200Y667500D03*
X90400D03*
X85600D03*
X190944Y577166D03*
X187795D03*
X307567Y273592D03*
X304548Y272508D03*
Y261008D03*
X334107Y291354D03*
Y279854D03*
X307567Y349192D03*
X304267Y348092D03*
Y336592D03*
X307567Y335492D03*
Y323992D03*
X304267Y322892D03*
Y311392D03*
X307567Y310292D03*
Y298792D03*
X304267Y297692D03*
Y286192D03*
X334582Y341721D03*
Y330221D03*
X328187Y342816D03*
X328182Y329124D03*
Y317624D03*
X334593Y316584D03*
Y305084D03*
X328182Y303977D03*
Y292477D03*
X307567Y285092D03*
X304267Y373292D03*
Y361792D03*
X307567Y360692D03*
X328182Y379518D03*
Y368018D03*
X334582Y366974D03*
Y355474D03*
X328187Y354316D03*
X335000Y621200D03*
Y615400D03*
Y610200D03*
X325600Y640100D03*
X330400D03*
X335200D03*
X315520Y711720D03*
X320320D03*
X325120D03*
X588647Y28007D03*
X603943Y42806D03*
X608143Y42906D03*
X603943Y47006D03*
X608043D03*
X603747Y71407D03*
X900600Y201239D03*
G54D42*
X845198Y552063D03*
X837066Y543931D03*
G54D12*
X66435Y8514D03*
X61435D03*
X56435D03*
X51435D03*
X46435D03*
X41435D03*
X36435D03*
X31435D03*
X26435D03*
X21435D03*
X16435D03*
X8514Y10593D03*
Y15593D03*
Y20593D03*
Y25593D03*
Y30593D03*
Y35593D03*
Y40593D03*
Y45593D03*
Y50593D03*
Y55593D03*
Y60593D03*
X43000Y59500D03*
X51000D03*
X34000Y59400D03*
X8514Y65593D03*
Y70593D03*
Y75593D03*
Y80593D03*
Y85593D03*
Y90593D03*
Y95593D03*
Y100593D03*
Y105593D03*
Y110593D03*
Y115593D03*
Y120593D03*
Y125593D03*
Y130593D03*
Y135593D03*
Y140593D03*
Y145593D03*
Y150593D03*
Y155593D03*
Y160593D03*
Y165593D03*
Y170593D03*
Y175593D03*
Y180593D03*
Y185593D03*
Y190593D03*
Y195593D03*
Y200593D03*
Y205593D03*
Y210593D03*
Y215593D03*
Y220593D03*
Y225593D03*
Y230593D03*
Y235593D03*
Y240593D03*
Y245593D03*
Y250593D03*
Y255593D03*
Y260593D03*
Y265593D03*
Y270593D03*
Y275593D03*
Y280593D03*
Y285593D03*
Y290593D03*
Y295593D03*
Y300593D03*
Y305593D03*
Y310593D03*
Y315593D03*
Y320593D03*
Y325593D03*
Y330593D03*
Y335593D03*
Y340593D03*
Y345593D03*
Y350593D03*
Y355593D03*
Y360593D03*
Y365593D03*
Y370593D03*
Y375593D03*
Y380593D03*
Y385593D03*
Y390593D03*
Y395593D03*
Y400593D03*
Y405593D03*
Y410593D03*
Y415593D03*
Y420593D03*
Y425593D03*
Y430593D03*
Y435593D03*
Y440593D03*
Y445593D03*
Y450593D03*
Y455593D03*
Y460593D03*
Y465593D03*
Y470593D03*
Y475593D03*
Y480593D03*
Y485593D03*
Y490593D03*
Y495593D03*
Y500593D03*
Y505593D03*
Y510593D03*
Y515593D03*
Y520593D03*
Y525593D03*
Y530593D03*
Y535593D03*
Y540593D03*
Y545593D03*
Y550593D03*
Y555593D03*
Y560593D03*
Y565593D03*
X37660Y566400D03*
X64427Y538836D03*
X64701Y564416D03*
X61100Y546700D03*
X8514Y570593D03*
Y575593D03*
Y580593D03*
Y585593D03*
Y590593D03*
Y595593D03*
Y600593D03*
Y605593D03*
Y610593D03*
Y615593D03*
Y620593D03*
Y625593D03*
Y630593D03*
Y635593D03*
X42597Y571789D03*
X64701Y570716D03*
X8514Y640593D03*
Y645593D03*
Y650593D03*
Y655593D03*
Y660593D03*
Y665593D03*
Y670593D03*
Y675593D03*
Y680593D03*
Y685593D03*
Y690593D03*
Y695593D03*
Y700593D03*
Y705593D03*
Y710593D03*
X50400Y663700D03*
X50500Y667900D03*
X60600Y670900D03*
X65900Y671000D03*
X65714Y665850D03*
X60800Y660900D03*
X60700Y665900D03*
X65700Y660900D03*
X64884Y650984D03*
X37961Y659909D03*
X41100Y671800D03*
X8514Y715593D03*
Y720593D03*
X9942Y725256D03*
X12178Y729728D03*
X14414Y734200D03*
X16650Y738672D03*
X18886Y743144D03*
X21122Y747617D03*
X23358Y752089D03*
X111683Y63266D03*
Y58266D03*
Y23266D03*
Y18266D03*
Y13266D03*
X111435Y8514D03*
X106435D03*
X101435D03*
X96435D03*
X91435D03*
X86435D03*
X81435D03*
X76435D03*
X71435D03*
X111683Y118266D03*
Y113266D03*
Y108266D03*
Y103266D03*
Y98266D03*
Y93266D03*
Y88266D03*
Y83266D03*
Y78266D03*
Y73266D03*
Y68266D03*
X90768Y69755D03*
X82768D03*
X73768Y69655D03*
X111683Y203266D03*
Y198266D03*
Y193266D03*
Y188266D03*
Y183266D03*
Y178266D03*
Y173266D03*
Y168266D03*
Y163266D03*
Y158266D03*
Y153266D03*
Y148266D03*
Y278266D03*
Y273266D03*
Y268266D03*
Y263266D03*
Y258266D03*
Y253266D03*
Y248266D03*
Y243266D03*
Y238266D03*
Y233266D03*
Y228266D03*
Y223266D03*
Y218266D03*
Y213266D03*
Y208266D03*
Y348266D03*
Y343266D03*
Y338266D03*
Y333266D03*
Y328266D03*
Y323266D03*
Y318266D03*
Y313266D03*
Y308266D03*
Y303266D03*
Y298266D03*
Y293266D03*
Y288266D03*
Y283266D03*
Y418266D03*
Y413266D03*
Y408266D03*
Y403266D03*
Y398266D03*
Y393266D03*
Y388266D03*
Y383266D03*
Y378266D03*
Y373266D03*
Y368266D03*
Y363266D03*
Y358266D03*
Y353266D03*
X104000Y475500D03*
X105350Y511850D03*
X89899Y564415D03*
X119400Y511500D03*
X135012Y510200D03*
X94473Y547093D03*
X138900Y525999D03*
X136974Y534479D03*
X120500Y504600D03*
X140400Y607850D03*
X137000D03*
X130700D03*
X135706Y621187D03*
X119900Y621000D03*
X131200Y620600D03*
X89901Y587466D03*
X85400Y629784D03*
X86300Y703200D03*
Y708000D03*
X127100Y647000D03*
X123100D03*
X119000D03*
X139916Y709422D03*
X130019Y709695D03*
X139916Y705822D03*
X130019Y706095D03*
X135019D03*
X70700Y671000D03*
X70800Y660700D03*
X70600Y665800D03*
X73427Y699285D03*
X104550Y647050D03*
X104850Y639150D03*
X111300Y705500D03*
X76395Y755266D03*
X81395D03*
X86395D03*
X91395D03*
X96395D03*
X101395D03*
X106395D03*
X111395D03*
X116395D03*
X121395D03*
X126395D03*
X131395D03*
X136395D03*
X141395D03*
X108928Y744775D03*
X113928D03*
X118928D03*
X123928D03*
X103928D03*
X98928D03*
X93928D03*
X139916Y713022D03*
Y716622D03*
Y720222D03*
Y723822D03*
X130019Y713295D03*
Y716895D03*
Y720495D03*
X135019Y710595D03*
Y723595D03*
Y719095D03*
Y714845D03*
X130019Y724095D03*
X148000Y469000D03*
X196100Y482200D03*
X170870Y492270D03*
X198700Y513500D03*
X203350Y506700D03*
X188600Y531500D03*
X203500Y513500D03*
X191398Y509000D03*
X156297Y558267D03*
X211700Y513500D03*
X208700Y529100D03*
X207500Y502412D03*
X145000Y497600D03*
X200963Y636600D03*
X212923Y615000D03*
X191210Y617900D03*
X203300Y628900D03*
X196700Y704985D03*
X201700D03*
X206700D03*
X211700D03*
X191700D03*
X166500Y640300D03*
X191766Y679920D03*
X211706Y645349D03*
X208200Y645500D03*
X151130Y703440D03*
X184807Y643963D03*
X188500Y686800D03*
X146395Y755266D03*
X151395D03*
X156395D03*
X161395D03*
X166395D03*
X171395D03*
X176395D03*
X181395D03*
X186395D03*
X191395D03*
X196395D03*
X201395D03*
X206395D03*
X211395D03*
X213900Y474650D03*
X227100Y490300D03*
X275300Y467300D03*
X234648Y540453D03*
X221960Y504230D03*
X222500Y536161D03*
X279600Y527900D03*
X279450Y577970D03*
X260850Y603537D03*
X274800Y607500D03*
X258600Y613100D03*
X254208Y603995D03*
X254043Y598359D03*
X247088Y610236D03*
X254821Y627000D03*
X255228Y631071D03*
X278150Y637250D03*
X229800Y593200D03*
X246800Y589600D03*
X261900Y588900D03*
X245400Y581800D03*
X264358Y608152D03*
X241300Y635900D03*
X228900Y635800D03*
X222500Y630200D03*
X218800Y635600D03*
X221800Y614800D03*
X246500Y602500D03*
X234000Y628400D03*
X230900Y581600D03*
X270300Y622315D03*
X281500Y598419D03*
X221700Y704985D03*
X226700D03*
X216700D03*
X267500Y645600D03*
X280500Y708100D03*
X269003Y704337D03*
X282620Y640950D03*
X262826Y662274D03*
X245100Y639500D03*
X219200Y645300D03*
X230270Y645933D03*
X247725Y656375D03*
X261900Y699300D03*
X266550Y675750D03*
X247825Y670375D03*
X245971Y698400D03*
X235100Y679921D03*
X221575Y695400D03*
X279400Y686400D03*
X216395Y755266D03*
X221395D03*
X226395D03*
X231395D03*
X236395D03*
X241395D03*
X246395D03*
X251395D03*
X256395D03*
X261395D03*
X266395D03*
X271395D03*
X276395D03*
X281395D03*
X280600Y711700D03*
X282353Y740020D03*
X268820Y715100D03*
X262645Y712155D03*
X330546Y8514D03*
X325546D03*
X320546D03*
X315546D03*
X310546D03*
X305546D03*
X300546D03*
X296034Y9002D03*
Y14002D03*
Y19002D03*
Y24002D03*
Y29002D03*
Y34002D03*
Y39002D03*
Y44002D03*
Y49002D03*
Y54002D03*
Y59002D03*
Y64002D03*
Y69002D03*
Y74002D03*
Y79002D03*
Y84002D03*
Y89002D03*
Y94002D03*
Y99002D03*
Y104002D03*
Y109002D03*
Y114002D03*
Y119002D03*
Y124002D03*
Y129002D03*
Y134002D03*
X345069Y108533D03*
X340080Y108432D03*
X348900Y115400D03*
X340706Y128612D03*
X305703Y202696D03*
X355600Y172900D03*
X306407Y206057D03*
X355300Y179300D03*
X354282Y187718D03*
Y191718D03*
X296034Y139002D03*
X321432Y279090D03*
X321281Y266486D03*
X321197Y254433D03*
X306446Y247874D03*
X323842Y219284D03*
X305498Y213824D03*
X305382Y227474D03*
X323800Y227000D03*
X323700Y230600D03*
X321432Y342082D03*
Y329484D03*
Y316885D03*
X321882Y304374D03*
Y291874D03*
X320832Y367479D03*
X321432Y354681D03*
X320932Y377074D03*
X340606Y389899D03*
X305350Y514300D03*
X292200Y542473D03*
X285800Y549394D03*
X346440Y527500D03*
X350879Y520400D03*
X352734Y541826D03*
X355700Y510000D03*
X344600Y511800D03*
X326900Y507700D03*
X312289Y535181D03*
X318200Y522900D03*
X299100Y589200D03*
X341750Y630790D03*
X342330Y620300D03*
X344940Y617720D03*
X292400Y637000D03*
X341690Y609930D03*
X341210Y602420D03*
X330800Y602610D03*
X317572Y603183D03*
X305470Y623734D03*
X311386Y633450D03*
X306300Y638600D03*
X301286Y638650D03*
X301386Y633650D03*
X306286D03*
X311186Y638550D03*
X307542Y588138D03*
X297118Y668882D03*
X294804Y695204D03*
X292400Y640500D03*
X332824Y684270D03*
X348314Y643853D03*
X332800Y691970D03*
X318000Y678270D03*
X304100Y666500D03*
X300720Y704920D03*
X300520Y710020D03*
X290620Y710120D03*
X295634Y710070D03*
X290720Y705120D03*
X295620D03*
X351547Y645938D03*
X355100Y651827D03*
X301186Y643650D03*
X306486Y643750D03*
X311286D03*
X314398Y670254D03*
X340000Y662200D03*
X352800Y702960D03*
X286395Y755266D03*
X291395D03*
X296395D03*
X301395D03*
X306395D03*
X311395D03*
X316395D03*
X321395D03*
X326395D03*
X331395D03*
X336395D03*
X298570Y743670D03*
X306470Y743570D03*
X300620Y715220D03*
X290520Y715120D03*
X295820Y715220D03*
X380500Y33500D03*
Y30000D03*
X382631Y48200D03*
X382547Y52800D03*
X375300Y62150D03*
X384000Y30000D03*
X375300Y72050D03*
X357500Y104200D03*
X394070Y80840D03*
X385964Y80089D03*
X382500Y88000D03*
X363400Y115950D03*
X376000Y78400D03*
X428740Y179528D03*
X405100Y159300D03*
X400000Y159200D03*
X365900Y198500D03*
X362150Y214174D03*
X364000Y240100D03*
X379448Y487250D03*
X368100Y513100D03*
X387800Y529400D03*
X367500Y526800D03*
X393100Y564400D03*
X362801Y548097D03*
X366900Y499942D03*
X365164Y612620D03*
X358864D03*
X396200Y597200D03*
X394800Y609700D03*
X358646Y596456D03*
X371400Y606400D03*
X358800Y606300D03*
X365300Y606500D03*
X371400Y612700D03*
X371300Y618800D03*
X365500Y619000D03*
X358900Y618800D03*
X359000Y635600D03*
X360980Y582586D03*
X394300Y576600D03*
X372951Y576851D03*
X377714Y631280D03*
X368399Y567372D03*
X399754Y706071D03*
X388418Y650549D03*
X385700Y641300D03*
X374200Y645871D03*
X374252Y641029D03*
X386050Y701200D03*
X389168Y743572D03*
X391404Y739100D03*
X393640Y734628D03*
X395876Y730156D03*
X398112Y725684D03*
X399754Y716071D03*
Y711071D03*
X379450Y714400D03*
X468000Y31500D03*
Y39500D03*
X464000Y35500D03*
X468000Y35400D03*
X472000Y35500D03*
X499721Y46102D03*
X499623Y49524D03*
X435000Y29000D03*
X438500Y25500D03*
Y32500D03*
X446788Y55180D03*
X457086Y179528D03*
X442913D03*
X471260D03*
X556510Y53626D03*
X504900Y18200D03*
X508646Y18386D03*
X518890Y59730D03*
X548550Y76480D03*
X525000Y76300D03*
X525200Y80900D03*
X513379Y103325D03*
X502379Y103194D03*
X556710Y64726D03*
X543750Y76480D03*
X513779Y179528D03*
X527953D03*
X542126D03*
X556299D03*
X608847Y34607D03*
X614032Y33307D03*
X621747Y63307D03*
X626647Y77507D03*
Y72507D03*
Y67507D03*
X576624Y193205D03*
Y198205D03*
Y203205D03*
Y208205D03*
Y213205D03*
Y223205D03*
Y228205D03*
Y233205D03*
Y238205D03*
Y243205D03*
Y248205D03*
Y253205D03*
Y258205D03*
Y263205D03*
Y268205D03*
Y273205D03*
Y278205D03*
Y333205D03*
Y338205D03*
Y343205D03*
Y348205D03*
Y353205D03*
Y358205D03*
Y363205D03*
Y368205D03*
Y373205D03*
Y378205D03*
Y383205D03*
Y388205D03*
Y393205D03*
Y398205D03*
Y403205D03*
Y408205D03*
Y413205D03*
Y418205D03*
Y423205D03*
Y428205D03*
Y433205D03*
Y438205D03*
Y443205D03*
Y448205D03*
Y498205D03*
Y503205D03*
Y508205D03*
Y513205D03*
Y518205D03*
Y523205D03*
Y528205D03*
Y533205D03*
Y538205D03*
Y543205D03*
Y548205D03*
Y553205D03*
Y558205D03*
Y563205D03*
Y568205D03*
Y573205D03*
Y578205D03*
Y583205D03*
Y588205D03*
X578710Y592712D03*
X580946Y597184D03*
X583182Y601656D03*
X585418Y606129D03*
X587654Y610601D03*
X635975Y621407D03*
X640975D03*
X715546Y8514D03*
X710546D03*
X705546D03*
X700546D03*
X695546D03*
X710550Y18550D03*
X700065Y135985D03*
Y125985D03*
Y115985D03*
X710065D03*
Y125985D03*
Y135985D03*
X700065Y155985D03*
X710065D03*
Y145985D03*
X696159Y225829D03*
X698909Y278104D03*
X700065Y265985D03*
Y255985D03*
Y245985D03*
Y235985D03*
X710065D03*
Y245985D03*
Y255985D03*
Y265985D03*
X709625Y275991D03*
X710065Y325985D03*
Y315985D03*
X711574Y285985D03*
X708307Y295429D03*
X710065Y305985D03*
Y335985D03*
Y345985D03*
X700065Y385985D03*
Y395985D03*
Y405985D03*
Y415985D03*
X710065Y375985D03*
Y355985D03*
Y365985D03*
Y455985D03*
X684399Y466984D03*
Y471984D03*
X706275Y445986D03*
X663500Y484000D03*
Y489000D03*
Y494000D03*
X692282Y476720D03*
X700900Y423800D03*
X693392Y520482D03*
X683392D03*
X688392D03*
X705080Y521247D03*
X694272Y495786D03*
X713189Y524511D03*
X707283D03*
X701378D03*
X695472D03*
X689567D03*
X683661D03*
X677756D03*
X662400Y519500D03*
X666800D03*
X657199Y530195D03*
X671850Y524511D03*
X645975Y621407D03*
X650975D03*
X655975D03*
X660975D03*
X665975D03*
X670975D03*
X675975D03*
X680975D03*
X685975D03*
X690975D03*
X695975D03*
X700975D03*
X705975D03*
X710975D03*
X715975D03*
X785546Y8514D03*
X780546D03*
X775546D03*
X770546D03*
X765546D03*
X760546D03*
X755546D03*
X750546D03*
X745546D03*
X740546D03*
X735546D03*
X730546D03*
X725546D03*
X720546D03*
X770065Y55985D03*
Y65985D03*
Y75985D03*
X750065Y85985D03*
X770065D03*
X760065D03*
X740065D03*
X730065Y95985D03*
X760065D03*
X780065D03*
X770065D03*
Y105985D03*
X780065D03*
Y115985D03*
X730065Y135985D03*
Y125985D03*
Y115985D03*
Y105985D03*
X750065Y95985D03*
X740065D03*
X750065Y105985D03*
X760065D03*
X740065D03*
X750065Y115985D03*
X760065D03*
X770065D03*
X740065D03*
X750065Y125985D03*
X760065D03*
X770065D03*
X780065D03*
X740065D03*
X750065Y135985D03*
X760065D03*
X770065D03*
X780065D03*
X740065D03*
X720065Y105985D03*
Y115985D03*
Y125985D03*
Y135985D03*
Y155985D03*
X780065D03*
X730065D03*
Y145985D03*
X750065D03*
X760065D03*
X770065D03*
X780065D03*
X740065D03*
X750065Y155985D03*
X760065D03*
X770065D03*
X740065D03*
X750065Y165985D03*
X760065D03*
X770065D03*
X740065D03*
X750065Y175985D03*
X760065D03*
X770065D03*
X740065D03*
X750065Y185985D03*
X760065D03*
X770065D03*
X740065D03*
X750065Y195985D03*
X760065D03*
X770065D03*
X740065D03*
X750065Y205985D03*
X760065D03*
X770065D03*
X740065D03*
X720065Y145985D03*
X730065Y215985D03*
X773469Y277001D03*
X780065Y275985D03*
X787817Y275879D03*
X750065Y215985D03*
X760065D03*
X770065D03*
X780065D03*
X740065D03*
X780065Y265985D03*
Y255985D03*
Y245985D03*
Y235985D03*
Y225985D03*
X770065Y265985D03*
Y255985D03*
Y245985D03*
Y235985D03*
Y225985D03*
X763133Y275881D03*
X759790Y263326D03*
X760065Y255985D03*
Y245985D03*
Y235985D03*
Y225985D03*
X750065Y275985D03*
Y265985D03*
Y255985D03*
Y245985D03*
Y235985D03*
Y225985D03*
X741608Y277171D03*
X740065Y265985D03*
Y255985D03*
Y245985D03*
Y235985D03*
Y225985D03*
X730830Y276087D03*
X730065Y265985D03*
Y255985D03*
X731766Y246017D03*
X730065Y235985D03*
X730190Y223549D03*
X720237Y223228D03*
X720065Y235985D03*
X721766Y246017D03*
X720065Y255985D03*
Y265985D03*
X718617Y275736D03*
X770065Y335985D03*
X760065D03*
X720065Y325985D03*
X760065D03*
X750065D03*
X740065D03*
X730065D03*
X720065Y315985D03*
X780065Y285985D03*
X770065D03*
X760065D03*
X750065Y295985D03*
X760065D03*
X770065D03*
X780065D03*
Y305985D03*
Y315985D03*
Y325985D03*
Y335985D03*
Y345985D03*
X770065Y305985D03*
Y315985D03*
Y325985D03*
Y345985D03*
X760065Y305985D03*
Y315985D03*
Y345985D03*
X750065Y305985D03*
Y315985D03*
Y335985D03*
Y345985D03*
X740065Y305985D03*
Y315985D03*
Y335985D03*
Y345985D03*
X730065D03*
Y335985D03*
Y315985D03*
X752500Y286000D03*
X740065Y295985D03*
X741000Y286000D03*
X730065Y305985D03*
X729486Y296094D03*
X729294Y285987D03*
X721574Y285985D03*
X719049Y296011D03*
X720065Y305985D03*
Y335985D03*
Y345985D03*
X750065Y415985D03*
X760065D03*
X770065D03*
X780065D03*
X730065D03*
X740065D03*
X750065Y405985D03*
X760065D03*
X770065D03*
X780065D03*
X730065D03*
X740065D03*
X780065Y395985D03*
X770065D03*
X760065D03*
X750065D03*
X740065D03*
X730065D03*
X720065Y375985D03*
X730065Y365985D03*
Y375985D03*
Y385985D03*
X750065D03*
X760065D03*
X770065D03*
X780065D03*
X740065D03*
X750065Y375985D03*
X760065D03*
X770065D03*
X780065D03*
X740065D03*
X750065Y365985D03*
X760065D03*
X770065D03*
X780065D03*
X740065D03*
X780065Y355985D03*
X770065D03*
X760065D03*
X750065D03*
X740065D03*
X730065D03*
X720065D03*
Y365985D03*
X783800Y422800D03*
X720065Y455985D03*
Y465985D03*
X750065D03*
X760065D03*
X770065D03*
X780065D03*
X730065D03*
X740065D03*
X780065Y455985D03*
X770065D03*
X760065D03*
X750065D03*
X740065D03*
X730065D03*
X750065Y445985D03*
X760065D03*
X770065D03*
X780065D03*
X730065D03*
X740065D03*
X750065Y435985D03*
X760065D03*
X770065D03*
X780065D03*
X740065D03*
X750065Y425985D03*
X760065D03*
X770065D03*
X780065D03*
X784604Y519082D03*
X758512Y534430D03*
X747107Y536580D03*
X739334Y524156D03*
X762679Y535537D03*
X742716Y536435D03*
X738779D03*
X782086D03*
X776181D03*
X770275D03*
X725000D03*
X719394Y536305D03*
X720975Y621407D03*
X725975D03*
X730975D03*
X735975D03*
X740975D03*
X745975D03*
X750975D03*
X755975D03*
X760975D03*
X765975D03*
X770975D03*
X775975D03*
X780975D03*
X785975D03*
X850546Y8514D03*
X845546D03*
X840546D03*
X835546D03*
X830546D03*
X825546D03*
X820546D03*
X815546D03*
X810546D03*
X805546D03*
X800546D03*
X795546D03*
X790546D03*
X820065Y105985D03*
Y135985D03*
Y125985D03*
Y115985D03*
X810065Y135985D03*
Y125985D03*
Y115985D03*
X790065Y105985D03*
X800065Y115985D03*
X790065D03*
Y125985D03*
X800065D03*
Y135985D03*
X790065D03*
X853436Y108917D03*
Y113717D03*
X853435Y90260D03*
Y95060D03*
X820065Y155985D03*
X810065D03*
X800065D03*
X790065D03*
X820065Y145985D03*
X810065D03*
X790065D03*
X800065D03*
X820313Y276188D03*
X810065Y275985D03*
X800065D03*
X820065Y265985D03*
Y255985D03*
Y245985D03*
Y235985D03*
Y225985D03*
X810065Y265985D03*
Y255985D03*
Y245985D03*
Y235985D03*
X800065Y265985D03*
Y255985D03*
Y245985D03*
Y235985D03*
X790065Y265985D03*
Y255985D03*
Y245985D03*
Y235985D03*
Y225985D03*
X820065Y305985D03*
Y295985D03*
Y285985D03*
X810065Y295985D03*
Y285985D03*
X800065D03*
X790065D03*
Y295985D03*
X800065D03*
X810065Y305985D03*
X810000Y314000D03*
X810065Y325985D03*
X800065Y305985D03*
Y315985D03*
Y325985D03*
Y335985D03*
Y345985D03*
X790065Y305985D03*
Y315985D03*
Y325985D03*
X791500Y336000D03*
X790065Y345985D03*
Y415985D03*
Y405985D03*
Y395985D03*
Y375985D03*
X800065D03*
X790065Y365985D03*
X800065D03*
Y355985D03*
X790065D03*
X809702Y416359D03*
X815600Y386200D03*
X800065Y455985D03*
Y465985D03*
X790065D03*
Y455985D03*
Y445985D03*
Y435985D03*
X790191Y426486D03*
X805771Y518743D03*
X789604Y519082D03*
X794604D03*
X825000Y536200D03*
X817519Y536435D03*
X811614D03*
X805708D03*
X841141D03*
X837204D03*
X799803D03*
X793897D03*
X787992D03*
X790975Y621407D03*
X795975D03*
X800975D03*
X805975D03*
X810975D03*
X815975D03*
X820975D03*
X825975D03*
X830975D03*
X835975D03*
X840975D03*
X854971Y637313D03*
Y642313D03*
Y647313D03*
Y652313D03*
Y657313D03*
Y662313D03*
Y667313D03*
Y672313D03*
Y677313D03*
Y682313D03*
Y687313D03*
Y692313D03*
Y697313D03*
Y702313D03*
Y707313D03*
Y712313D03*
X916683Y62377D03*
Y57377D03*
Y52377D03*
Y47377D03*
Y42377D03*
Y37377D03*
Y32377D03*
Y27377D03*
Y22377D03*
Y17377D03*
X915546Y8514D03*
X910546D03*
X905546D03*
X900546D03*
X916683Y132377D03*
Y127377D03*
Y122377D03*
Y117377D03*
Y112377D03*
Y107377D03*
Y102377D03*
Y97377D03*
Y92377D03*
Y87377D03*
Y82377D03*
Y77377D03*
Y72377D03*
Y67377D03*
Y207377D03*
Y202377D03*
Y197377D03*
Y192377D03*
Y187377D03*
Y182377D03*
Y177377D03*
Y172377D03*
Y167377D03*
Y162377D03*
Y157377D03*
Y152377D03*
Y147377D03*
Y142377D03*
Y137377D03*
Y277377D03*
Y272377D03*
Y267377D03*
Y262377D03*
Y257377D03*
Y252377D03*
Y247377D03*
Y242377D03*
Y237377D03*
Y232377D03*
Y227377D03*
Y222377D03*
Y217377D03*
Y212377D03*
X897195Y275688D03*
X902195D03*
Y270688D03*
X897195D03*
X916683Y347377D03*
Y342377D03*
Y337377D03*
Y332377D03*
Y327377D03*
Y322377D03*
Y317377D03*
Y312377D03*
Y307377D03*
Y302377D03*
Y297377D03*
Y292377D03*
Y287377D03*
Y282377D03*
X896030Y296330D03*
X901030D03*
X900995Y290712D03*
X895995D03*
X900819Y316367D03*
X895819D03*
X900716Y311058D03*
X895716D03*
X916683Y422377D03*
Y417377D03*
Y412377D03*
Y407377D03*
Y402377D03*
Y397377D03*
Y392377D03*
Y387377D03*
Y382377D03*
Y377377D03*
Y372377D03*
Y367377D03*
Y362377D03*
Y357377D03*
Y352377D03*
Y492377D03*
Y487377D03*
Y482377D03*
Y477377D03*
Y472377D03*
Y467377D03*
Y462377D03*
Y457377D03*
Y452377D03*
Y447377D03*
Y442377D03*
Y437377D03*
Y432377D03*
Y427377D03*
Y562377D03*
Y557377D03*
Y552377D03*
Y547377D03*
Y542377D03*
Y537377D03*
Y532377D03*
Y527377D03*
Y522377D03*
Y517377D03*
Y512377D03*
Y507377D03*
Y502377D03*
Y497377D03*
Y637377D03*
Y632377D03*
Y627377D03*
Y622377D03*
Y617377D03*
Y612377D03*
Y607377D03*
Y602377D03*
Y597377D03*
Y592377D03*
Y587377D03*
Y582377D03*
Y577377D03*
Y572377D03*
Y567377D03*
Y707377D03*
Y702377D03*
Y697377D03*
Y692377D03*
Y687377D03*
Y682377D03*
Y677377D03*
Y672377D03*
Y667377D03*
Y662377D03*
Y657377D03*
Y652377D03*
Y647377D03*
Y642377D03*
X901041Y753684D03*
X903277Y749212D03*
X905513Y744740D03*
X907749Y740268D03*
X909985Y735796D03*
X912221Y731323D03*
X914457Y726851D03*
X916683Y722377D03*
Y717377D03*
Y712377D03*
G54D36*
X706299Y83661D03*
Y201771D03*
X804724Y83661D03*
Y201772D03*
G54D35*
X488838Y164744D03*
G54D14*
X34652Y111485D03*
X33297Y703990D03*
X148206Y21054D03*
X261147Y405580D03*
X486498Y356293D03*
X807831Y734367D03*
X899219Y47960D03*
G54D34*
X488838Y137225D03*
G54D20*
X89764Y238386D03*
X309252Y413583D03*
G54D25*
X163189Y669291D03*
G54D30*
X339331Y91929D03*
X360669Y49803D03*
G54D21*
X90157Y413582D03*
X309055Y157677D03*
G54D15*
X70865Y98425D03*
Y472441D03*
X314960D03*
X364173Y740157D03*
X405511Y39370D03*
X587795Y307087D03*
X590551Y472441D03*
X612204Y606299D03*
X875984Y472441D03*
Y606299D03*
Y740157D03*
G54D19*
X49212D03*
X875984Y31496D03*
G54D16*
X67853Y558117D03*
X64277Y502177D03*
X106272Y547370D03*
X89899Y558115D03*
X69904Y502077D03*
X75399Y502179D03*
X81094Y502166D03*
X86699Y502300D03*
X97926D03*
X108371Y577258D03*
X86750Y567565D03*
X93048Y577014D03*
X86750Y573864D03*
X89899D03*
X75197Y572437D03*
X194094Y539370D03*
X203542Y545671D03*
X197243Y539371D03*
X194093Y564569D03*
X190944D03*
X194093Y555120D03*
X184646D03*
X153149Y536221D03*
X165748Y558268D03*
X172048Y555120D03*
X187925Y564617D03*
X168898Y561417D03*
X206692Y555120D03*
X175196Y589764D03*
X194093Y574016D03*
Y567718D03*
X190944Y574016D03*
Y567718D03*
X172048Y589764D03*
X168898D03*
X187844Y574065D03*
X184645Y574166D03*
X187746Y567669D03*
X184695Y567666D03*
X184646Y570867D03*
X168898Y570866D03*
X156299Y586614D03*
Y580315D03*
X159449Y567717D03*
X156299Y570866D03*
X200393Y589764D03*
X187900Y589800D03*
X187794Y586614D03*
X203542Y589764D03*
X200393Y596063D03*
X203605Y605821D03*
X153149Y605513D03*
X206692Y592913D03*
X165748Y583464D03*
X209842D03*
X212992Y586614D03*
X148249Y695765D03*
X222440Y605512D03*
X225900Y615000D03*
X353700Y670900D03*
X668847Y27107D03*
X663847D03*
X658847D03*
X653847D03*
X716100Y442100D03*
X721100D03*
X850730Y350483D03*
X841116Y348914D03*
X820059Y331701D03*
X857020Y383172D03*
Y379572D03*
Y386772D03*
X815541Y354089D03*
X847720Y371072D03*
X804000Y441100D03*
X799000D03*
X883222Y59214D03*
X888022D03*
X892822D03*
X897622D03*
X880922Y63714D03*
X885722D03*
X890522D03*
X895322D03*
X900122D03*
X875272Y186265D03*
X878872D03*
X860872D03*
X871672D03*
X868072D03*
X864472D03*
X878372Y191265D03*
X878872Y196265D03*
X864472D03*
X868072D03*
X871672D03*
X875272D03*
X865372Y191265D03*
X873872D03*
X869622D03*
X860872Y196265D03*
Y191265D03*
X871420Y383172D03*
X875020D03*
Y379572D03*
X871420D03*
X867820D03*
X860620D03*
X864220D03*
X875020Y386772D03*
X871420D03*
X867820D03*
X860620D03*
X864220D03*
X867820Y383172D03*
X860620D03*
X864220D03*
G54D17*
X28782Y555119D03*
X34132Y521245D03*
X34175Y526969D03*
X29165Y532612D03*
X29058Y538228D03*
X29158Y543855D03*
X28800Y549474D03*
X33697Y560866D03*
X67852Y583313D03*
Y586463D03*
X118197Y490300D03*
X71002Y577013D03*
X186254Y463761D03*
X179000Y499800D03*
X184645Y539370D03*
X184646Y577166D03*
X187795Y592914D03*
Y602363D03*
X304800Y554443D03*
X304124Y570227D03*
X334923Y579949D03*
X421653Y126378D03*
X428740Y121654D03*
Y135827D03*
X421653Y183071D03*
Y140551D03*
Y154725D03*
X428740Y150000D03*
X421653Y168898D03*
X428740Y164173D03*
X435827Y126378D03*
X450000D03*
X464173D03*
X442913Y121654D03*
X457086D03*
X471260D03*
X442913Y135827D03*
X457086D03*
X471260D03*
X435827Y183071D03*
X450000D03*
X464173D03*
X435827Y140551D03*
X450000D03*
X464173D03*
X435827Y154725D03*
X442913Y150000D03*
X450000Y154725D03*
X457086Y150000D03*
X464173Y154725D03*
X471260Y150000D03*
X435827Y168898D03*
X442913Y164173D03*
X450000Y168898D03*
X457086Y164173D03*
X464173Y168898D03*
X471260Y164173D03*
X506693Y126378D03*
X520866D03*
X535039D03*
X549212D03*
X513779Y121654D03*
X527953D03*
X542126D03*
X556299D03*
X513779Y135827D03*
X527953D03*
X542126D03*
X556299D03*
X506693Y183071D03*
X520866D03*
X535039D03*
X549212D03*
X506693Y140551D03*
X520866D03*
X535039D03*
X549212D03*
X506693Y154725D03*
X513779Y150000D03*
X520866Y154725D03*
X527953Y150000D03*
X535039Y154725D03*
X542126Y150000D03*
X549212Y154725D03*
X556299Y150000D03*
X506693Y168898D03*
X513779Y164173D03*
X520866Y168898D03*
X527953Y164173D03*
X535039Y168898D03*
X542126Y164173D03*
X549212Y168898D03*
X556299Y164173D03*
X576649Y39585D03*
X575300Y45967D03*
X725288Y405950D03*
X740500Y426800D03*
X716536Y523519D03*
X728036D03*
X854596Y155288D03*
X840122Y156614D03*
X843160Y169467D03*
X858632Y216929D03*
X808188Y404950D03*
X856720Y409372D03*
X822300Y418900D03*
X897803Y207684D03*
X902803D03*
X897803Y217684D03*
Y212684D03*
X902803Y217684D03*
Y212684D03*
X876451Y407949D03*
X880665Y410841D03*
X885665D03*
X890665D03*
X895665D03*
X900665D03*
G54D38*
X715000Y547027D03*
X705853Y549017D03*
X713985Y557149D03*
X696624Y548249D03*
X704756Y556381D03*
X683369Y549269D03*
X691501Y557401D03*
X681989Y540183D03*
X690121Y548315D03*
X668195Y541742D03*
X676327Y549874D03*
X655092Y536171D03*
X663224Y544303D03*
X785434Y551934D03*
X775934Y550934D03*
X784066Y559066D03*
X765434Y549934D03*
X773566Y558066D03*
X753434Y545434D03*
X761566Y553566D03*
X725853Y547117D03*
X733985Y555249D03*
X723132Y555159D03*
X822434Y550434D03*
X830566Y558566D03*
X809934Y545434D03*
X818066Y553566D03*
X803934Y551934D03*
X812066Y560066D03*
X794934Y551434D03*
X803066Y559566D03*
X793566Y560066D03*
G54D41*
X811024Y24409D03*
G54D27*
X346457Y57007D03*
%LPC*%
G75*
G54D43*
G01X-36569Y-23804D02*
Y-103804D01*
G01D02*
X1258031D01*
G01X-40569Y-7804D02*
G02I-12000J0D01*
G01X-45719D02*
G02I-6850J0D01*
G01X-52569Y-23804D02*
Y8196D01*
G01X-36569Y-23804D02*
X1258031D01*
G01X-36569Y-59304D02*
X1258031D01*
G01X-36569Y-7804D02*
X-68569D01*
G01X470531Y-23804D02*
Y-103804D01*
G01X608031Y-23804D02*
Y-103804D01*
G01X723031Y-23804D02*
Y-103804D01*
G01X890531Y-23804D02*
Y-103804D01*
G01X1060531Y-23804D02*
Y-103804D01*
G01X1258031Y-23804D02*
Y-103804D01*
G01X1286031Y-7804D02*
G02I-12000J0D01*
G01X1280881D02*
G02I-6850J0D01*
G01X1274031Y-23804D02*
Y8196D01*
G01X1290031Y-7804D02*
X1258031D01*
G54D44*
G01X-9023Y-84471D02*
X-8149Y-83596D01*
X-7494Y-82138D01*
X-7057Y-80095D01*
X-7494Y-78346D01*
X-8367Y-77179D01*
X-9896Y-76304D01*
X-15791D01*
Y-93804D01*
X-8586D01*
X-7057Y-92638D01*
X-6184Y-90887D01*
X-5747Y-88846D01*
X-6184Y-86804D01*
X-7494Y-85054D01*
X-9023Y-84471D01*
X-15791D01*
G01X3674Y-93804D02*
Y-82138D01*
G01Y-84471D02*
X4766Y-83304D01*
X5858Y-82429D01*
X7386Y-82138D01*
X8477Y-82429D01*
X9788Y-83304D01*
G01X19646Y-99054D02*
X20956Y-99637D01*
X22703Y-99054D01*
X23794Y-97888D01*
X24668Y-96429D01*
X25977Y-91763D01*
X28816Y-82138D01*
G01X21829D02*
X25977Y-91763D01*
G01X45224Y-83596D02*
X43696Y-82429D01*
X42386Y-82138D01*
X40639Y-82721D01*
X39329Y-83887D01*
X38456Y-85929D01*
X38237Y-87971D01*
X38456Y-90013D01*
X39329Y-91763D01*
X40639Y-93221D01*
X42386Y-93804D01*
X43914Y-93221D01*
X45224Y-92054D01*
G01X55956Y-85929D02*
X62943D01*
X62288Y-83887D01*
X61196Y-82721D01*
X59668Y-82138D01*
X58139Y-82429D01*
X56829Y-83304D01*
X55956Y-85346D01*
X55519Y-87096D01*
Y-88846D01*
X55956Y-90596D01*
X57048Y-92346D01*
X58358Y-93512D01*
X59886Y-93804D01*
X61414Y-93221D01*
X62943Y-91471D01*
G01X99034Y-77763D02*
X97724Y-76887D01*
X96196Y-76304D01*
X94449D01*
X92484Y-77179D01*
X90956Y-78637D01*
X89864Y-80388D01*
X88991Y-83304D01*
X88772Y-85929D01*
X89209Y-88554D01*
X89864Y-90304D01*
X91174Y-92054D01*
X92703Y-93221D01*
X94231Y-93804D01*
X95759D01*
X97288Y-93221D01*
X98598Y-92346D01*
X99690Y-91180D01*
G01X115661Y-93804D02*
Y-82138D01*
G01Y-84179D02*
X114788Y-83013D01*
X113477Y-82429D01*
X111949Y-82138D01*
X110421Y-82721D01*
X109111Y-83887D01*
X108237Y-85637D01*
X107801Y-87971D01*
X108237Y-90304D01*
X109111Y-92054D01*
X110421Y-93221D01*
X111949Y-93804D01*
X113477Y-93512D01*
X114788Y-92638D01*
X115661Y-91471D01*
G01X125519Y-93804D02*
Y-82138D01*
G01Y-85054D02*
X126393Y-83596D01*
X127703Y-82429D01*
X129449Y-82138D01*
X130977Y-82429D01*
X132288Y-83596D01*
X132943Y-85637D01*
Y-93804D01*
G01X142146Y-99054D02*
X143456Y-99637D01*
X145203Y-99054D01*
X146294Y-97888D01*
X147168Y-96429D01*
X148477Y-91763D01*
X151316Y-82138D01*
G01X144329D02*
X148477Y-91763D01*
G01X164231Y-93804D02*
X162921Y-93512D01*
X161611Y-92346D01*
X160737Y-90304D01*
X160301Y-87971D01*
X160737Y-85637D01*
X161611Y-83596D01*
X162921Y-82429D01*
X164231Y-82138D01*
X165541Y-82429D01*
X166851Y-83596D01*
X167724Y-85637D01*
X167943Y-87971D01*
X167724Y-90304D01*
X166851Y-92346D01*
X165541Y-93512D01*
X164231Y-93804D01*
G01X178019D02*
Y-82138D01*
G01Y-85054D02*
X178893Y-83596D01*
X180203Y-82429D01*
X181949Y-82138D01*
X183477Y-82429D01*
X184788Y-83596D01*
X185443Y-85637D01*
Y-93804D01*
G01X214111Y-76304D02*
X219351D01*
G01X216731D02*
Y-93804D01*
G01X214111D02*
X219351D01*
G01X234231D02*
X232484Y-93512D01*
X230956Y-92346D01*
X229646Y-90596D01*
X228772Y-88554D01*
X228336Y-86221D01*
Y-83887D01*
X228772Y-81554D01*
X229646Y-79512D01*
X230956Y-77763D01*
X232484Y-76596D01*
X234231Y-76304D01*
X235977Y-76596D01*
X237506Y-77763D01*
X238816Y-79512D01*
X239690Y-81554D01*
X240126Y-83887D01*
Y-86221D01*
X239690Y-88554D01*
X238816Y-90596D01*
X237506Y-92346D01*
X235977Y-93512D01*
X234231Y-93804D01*
G01X246054D02*
Y-76304D01*
X251731Y-90887D01*
X257408Y-76304D01*
Y-93804D01*
G01X285639Y-99637D02*
X283456Y-96721D01*
X282364Y-93804D01*
Y-82138D01*
X283456Y-79221D01*
X285639Y-76304D01*
G01X298554Y-93804D02*
Y-76304D01*
X304231Y-90887D01*
X309908Y-76304D01*
Y-93804D01*
G01X321731Y-94387D02*
X321294Y-94096D01*
Y-93512D01*
X321731Y-93221D01*
X322168Y-93512D01*
Y-94096D01*
X321731Y-94387D01*
G01X335083Y-79221D02*
X336393Y-77471D01*
X337921Y-76596D01*
X339668Y-76304D01*
X341851Y-76887D01*
X343379Y-78346D01*
X343816Y-80095D01*
X343598Y-81846D01*
X342724Y-83304D01*
X338358Y-86221D01*
X336393Y-88262D01*
X335083Y-91180D01*
X334646Y-93804D01*
X343816D01*
G01X374231D02*
X372921Y-93512D01*
X371611Y-92346D01*
X370737Y-90304D01*
X370301Y-87971D01*
X370737Y-85637D01*
X371611Y-83596D01*
X372921Y-82429D01*
X374231Y-82138D01*
X375541Y-82429D01*
X376851Y-83596D01*
X377724Y-85637D01*
X377943Y-87971D01*
X377724Y-90304D01*
X376851Y-92346D01*
X375541Y-93512D01*
X374231Y-93804D01*
G01X388019D02*
Y-82138D01*
G01Y-85054D02*
X388893Y-83596D01*
X390203Y-82429D01*
X391949Y-82138D01*
X393477Y-82429D01*
X394788Y-83596D01*
X395443Y-85637D01*
Y-93804D01*
G01X409231D02*
Y-76304D01*
G01X422146Y-99054D02*
X423456Y-99637D01*
X425203Y-99054D01*
X426294Y-97888D01*
X427168Y-96429D01*
X428477Y-91763D01*
X431316Y-82138D01*
G01X424329D02*
X428477Y-91763D01*
G01X445323Y-99637D02*
X447506Y-96721D01*
X448598Y-93804D01*
Y-82138D01*
X447506Y-79221D01*
X445323Y-76304D01*
G01X176054Y-48804D02*
Y-31304D01*
X181731Y-45887D01*
X187408Y-31304D01*
Y-48804D01*
G01X199231D02*
X197921Y-48512D01*
X196611Y-47346D01*
X195737Y-45304D01*
X195301Y-42971D01*
X195737Y-40637D01*
X196611Y-38596D01*
X197921Y-37429D01*
X199231Y-37138D01*
X200541Y-37429D01*
X201851Y-38596D01*
X202724Y-40637D01*
X202943Y-42971D01*
X202724Y-45304D01*
X201851Y-47346D01*
X200541Y-48512D01*
X199231Y-48804D01*
G01X220661Y-31304D02*
Y-48804D01*
G01Y-46180D02*
X219788Y-47638D01*
X218477Y-48512D01*
X216949Y-48804D01*
X215203Y-48221D01*
X213893Y-46763D01*
X213019Y-45013D01*
X212801Y-42971D01*
X213019Y-40929D01*
X213893Y-39179D01*
X215203Y-37721D01*
X216949Y-37138D01*
X218477Y-37429D01*
X219569Y-38013D01*
X220661Y-39179D01*
G01X230956Y-40929D02*
X237943D01*
X237288Y-38887D01*
X236196Y-37721D01*
X234668Y-37138D01*
X233139Y-37429D01*
X231829Y-38304D01*
X230956Y-40346D01*
X230519Y-42096D01*
Y-43846D01*
X230956Y-45596D01*
X232048Y-47346D01*
X233358Y-48512D01*
X234886Y-48804D01*
X236414Y-48221D01*
X237943Y-46471D01*
G01X251731Y-48804D02*
Y-31304D01*
G01X504231Y-93804D02*
Y-76304D01*
X501611Y-79804D01*
G01Y-93804D02*
X506851D01*
G01X517583Y-86513D02*
X519111Y-84471D01*
X520421Y-83304D01*
X522168Y-82721D01*
X523696Y-83304D01*
X524788Y-84471D01*
X525661Y-86221D01*
X525879Y-88262D01*
X525661Y-90013D01*
X524788Y-91763D01*
X523477Y-93221D01*
X521949Y-93804D01*
X520203Y-93221D01*
X518674Y-91471D01*
X517801Y-88846D01*
X517583Y-85929D01*
X518019Y-82138D01*
X518674Y-80095D01*
X519766Y-78054D01*
X521294Y-76596D01*
X522823Y-76304D01*
X524351Y-76887D01*
X525443Y-78346D01*
G01X534428Y-90304D02*
X535737Y-92346D01*
X537484Y-93512D01*
X539449Y-93804D01*
X541196Y-93512D01*
X542943Y-92054D01*
X544034Y-90304D01*
X544253Y-88554D01*
X543816Y-86513D01*
X542288Y-85054D01*
X540759Y-84471D01*
X538794D01*
G01X540759D02*
X542069Y-83596D01*
X543161Y-82138D01*
X543598Y-80388D01*
X543161Y-78637D01*
X542069Y-77179D01*
X540104Y-76304D01*
X538139Y-76596D01*
X536174Y-77763D01*
G01X559351Y-93804D02*
Y-76304D01*
X551272Y-88846D01*
X562190D01*
G01X570083Y-79221D02*
X571393Y-77471D01*
X572921Y-76596D01*
X574668Y-76304D01*
X576851Y-76887D01*
X578379Y-78346D01*
X578816Y-80095D01*
X578598Y-81846D01*
X577724Y-83304D01*
X573358Y-86221D01*
X571393Y-88262D01*
X570083Y-91180D01*
X569646Y-93804D01*
X578816D01*
G01X491114Y-48804D02*
Y-31304D01*
X496354D01*
X498101Y-32179D01*
X499411Y-34221D01*
X499848Y-36554D01*
X499411Y-38887D01*
X498319Y-40637D01*
X496354Y-41513D01*
X491114D01*
G01X517784Y-32763D02*
X516474Y-31887D01*
X514946Y-31304D01*
X513199D01*
X511234Y-32179D01*
X509706Y-33637D01*
X508614Y-35388D01*
X507741Y-38304D01*
X507522Y-40929D01*
X507959Y-43554D01*
X508614Y-45304D01*
X509924Y-47054D01*
X511453Y-48221D01*
X512981Y-48804D01*
X514509D01*
X516038Y-48221D01*
X517348Y-47346D01*
X518440Y-46180D01*
G01X532227Y-39471D02*
X533101Y-38596D01*
X533756Y-37138D01*
X534193Y-35095D01*
X533756Y-33346D01*
X532883Y-32179D01*
X531354Y-31304D01*
X525459D01*
Y-48804D01*
X532664D01*
X534193Y-47638D01*
X535066Y-45887D01*
X535503Y-43846D01*
X535066Y-41804D01*
X533756Y-40054D01*
X532227Y-39471D01*
X525459D01*
G01X541431Y-54637D02*
X554531D01*
G01X560459Y-48804D02*
Y-31304D01*
X570503Y-48804D01*
Y-31304D01*
G01X582981Y-48804D02*
X581234Y-48512D01*
X579706Y-47346D01*
X578396Y-45596D01*
X577522Y-43554D01*
X577086Y-41221D01*
Y-38887D01*
X577522Y-36554D01*
X578396Y-34512D01*
X579706Y-32763D01*
X581234Y-31596D01*
X582981Y-31304D01*
X584727Y-31596D01*
X586256Y-32763D01*
X587566Y-34512D01*
X588440Y-36554D01*
X588876Y-38887D01*
Y-41221D01*
X588440Y-43554D01*
X587566Y-45596D01*
X586256Y-47346D01*
X584727Y-48512D01*
X582981Y-48804D01*
G01X633822Y-31304D02*
X639281Y-48804D01*
X644740Y-31304D01*
G01X661148Y-48804D02*
X652414D01*
Y-31304D01*
X661148D01*
G01X657654Y-39762D02*
X652414D01*
G01X669914Y-48804D02*
Y-31304D01*
X675373D01*
X677119Y-32179D01*
X678211Y-33346D01*
X678648Y-35679D01*
X678211Y-38013D01*
X676901Y-39471D01*
X675373Y-40346D01*
X669914D01*
G01X675373D02*
X678648Y-48804D01*
G01X691781Y-49387D02*
X691344Y-49096D01*
Y-48512D01*
X691781Y-48221D01*
X692218Y-48512D01*
Y-49096D01*
X691781Y-49387D01*
G01X661383Y-79221D02*
X662693Y-77471D01*
X664221Y-76596D01*
X665968Y-76304D01*
X668151Y-76887D01*
X669679Y-78346D01*
X670116Y-80095D01*
X669898Y-81846D01*
X669024Y-83304D01*
X664658Y-86221D01*
X662693Y-88262D01*
X661383Y-91180D01*
X660946Y-93804D01*
X670116D01*
G01X767364Y-76304D02*
Y-93804D01*
X776098D01*
G01X785083Y-79221D02*
X786393Y-77471D01*
X787921Y-76596D01*
X789668Y-76304D01*
X791851Y-76887D01*
X793379Y-78346D01*
X793816Y-80095D01*
X793598Y-81846D01*
X792724Y-83304D01*
X788358Y-86221D01*
X786393Y-88262D01*
X785083Y-91180D01*
X784646Y-93804D01*
X793816D01*
G01X808041Y-85054D02*
X812408D01*
Y-90304D01*
X811098Y-92054D01*
X809569Y-93221D01*
X807386Y-93804D01*
X805203Y-93221D01*
X803674Y-92054D01*
X802364Y-90304D01*
X801491Y-88262D01*
X801054Y-85929D01*
Y-83887D01*
X801491Y-82138D01*
X802364Y-80095D01*
X803674Y-78346D01*
X804984Y-77179D01*
X806731Y-76304D01*
X808259D01*
X810006Y-76887D01*
X811316Y-78054D01*
G01X819209Y-93804D02*
Y-76304D01*
X829253Y-93804D01*
Y-76304D01*
G01X836928Y-93804D02*
Y-76304D01*
X841294D01*
X843041Y-77179D01*
X844351Y-78346D01*
X845443Y-80095D01*
X846316Y-82138D01*
X846534Y-85054D01*
X846316Y-87971D01*
X845443Y-90013D01*
X844351Y-91763D01*
X843041Y-92929D01*
X841294Y-93804D01*
X836928D01*
G01X767364Y-31304D02*
Y-48804D01*
X776098D01*
G01X793161D02*
Y-37138D01*
G01Y-39179D02*
X792288Y-38013D01*
X790977Y-37429D01*
X789449Y-37138D01*
X787921Y-37721D01*
X786611Y-38887D01*
X785737Y-40637D01*
X785301Y-42971D01*
X785737Y-45304D01*
X786611Y-47054D01*
X787921Y-48221D01*
X789449Y-48804D01*
X790977Y-48512D01*
X792288Y-47638D01*
X793161Y-46471D01*
G01X802146Y-54054D02*
X803456Y-54637D01*
X805203Y-54054D01*
X806294Y-52888D01*
X807168Y-51429D01*
X808477Y-46763D01*
X811316Y-37138D01*
G01X804329D02*
X808477Y-46763D01*
G01X820956Y-40929D02*
X827943D01*
X827288Y-38887D01*
X826196Y-37721D01*
X824668Y-37138D01*
X823139Y-37429D01*
X821829Y-38304D01*
X820956Y-40346D01*
X820519Y-42096D01*
Y-43846D01*
X820956Y-45596D01*
X822048Y-47346D01*
X823358Y-48512D01*
X824886Y-48804D01*
X826414Y-48221D01*
X827943Y-46471D01*
G01X838674Y-48804D02*
Y-37138D01*
G01Y-39471D02*
X839766Y-38304D01*
X840858Y-37429D01*
X842386Y-37138D01*
X843477Y-37429D01*
X844788Y-38304D01*
G01X931781Y-93804D02*
X930034Y-93512D01*
X928506Y-92346D01*
X927196Y-90596D01*
X926322Y-88554D01*
X925886Y-86221D01*
Y-83887D01*
X926322Y-81554D01*
X927196Y-79512D01*
X928506Y-77763D01*
X930034Y-76596D01*
X931781Y-76304D01*
X933527Y-76596D01*
X935056Y-77763D01*
X936366Y-79512D01*
X937240Y-81554D01*
X937676Y-83887D01*
Y-86221D01*
X937240Y-88554D01*
X936366Y-90596D01*
X935056Y-92346D01*
X933527Y-93512D01*
X931781Y-93804D01*
G01X933527Y-89137D02*
X936148Y-93804D01*
G01X944478Y-76304D02*
Y-88846D01*
X945351Y-91471D01*
X947098Y-93221D01*
X949281Y-93804D01*
X951464Y-93221D01*
X953211Y-91471D01*
X954084Y-88846D01*
Y-76304D01*
G01X964161D02*
X969401D01*
G01X966781D02*
Y-93804D01*
G01X964161D02*
X969401D01*
G01X979259D02*
Y-76304D01*
X989303Y-93804D01*
Y-76304D01*
G01X1006584Y-77763D02*
X1005274Y-76887D01*
X1003746Y-76304D01*
X1001999D01*
X1000034Y-77179D01*
X998506Y-78637D01*
X997414Y-80388D01*
X996541Y-83304D01*
X996322Y-85929D01*
X996759Y-88554D01*
X997414Y-90304D01*
X998724Y-92054D01*
X1000253Y-93221D01*
X1001781Y-93804D01*
X1003309D01*
X1004838Y-93221D01*
X1006148Y-92346D01*
X1007240Y-91180D01*
G01X1019281Y-93804D02*
Y-85929D01*
X1014914Y-76304D01*
G01X1023648D02*
X1019281Y-85929D01*
G01X909478Y-48804D02*
Y-31304D01*
X913844D01*
X915591Y-32179D01*
X916901Y-33346D01*
X917993Y-35095D01*
X918866Y-37138D01*
X919084Y-40054D01*
X918866Y-42971D01*
X917993Y-45013D01*
X916901Y-46763D01*
X915591Y-47929D01*
X913844Y-48804D01*
X909478D01*
G01X928506Y-40929D02*
X935493D01*
X934838Y-38887D01*
X933746Y-37721D01*
X932218Y-37138D01*
X930689Y-37429D01*
X929379Y-38304D01*
X928506Y-40346D01*
X928069Y-42096D01*
Y-43846D01*
X928506Y-45596D01*
X929598Y-47346D01*
X930908Y-48512D01*
X932436Y-48804D01*
X933964Y-48221D01*
X935493Y-46471D01*
G01X946006Y-46763D02*
X947098Y-47929D01*
X948626Y-48804D01*
X949936D01*
X951246Y-48221D01*
X952119Y-47346D01*
X952556Y-46180D01*
X952338Y-44429D01*
X951464Y-43554D01*
X947534Y-41804D01*
X946661Y-39762D01*
X947098Y-38304D01*
X947971Y-37429D01*
X949281Y-37138D01*
X950591Y-37429D01*
X951901Y-38304D01*
G01X966781Y-37138D02*
Y-48804D01*
G01Y-32471D02*
X966344Y-32179D01*
Y-31596D01*
X966781Y-31304D01*
X967218Y-31596D01*
Y-32179D01*
X966781Y-32471D01*
G01X981224Y-53179D02*
X982753Y-54346D01*
X984499Y-54637D01*
X986027Y-54346D01*
X987338Y-52888D01*
X988211Y-50846D01*
Y-37138D01*
G01Y-39471D02*
X987338Y-38304D01*
X986027Y-37429D01*
X984499Y-37138D01*
X982753Y-37721D01*
X981661Y-38887D01*
X980787Y-40929D01*
X980351Y-42971D01*
X980569Y-44721D01*
X981443Y-46763D01*
X982753Y-48221D01*
X984499Y-48804D01*
X985809Y-48512D01*
X987338Y-47346D01*
X988211Y-46180D01*
G01X998069Y-48804D02*
Y-37138D01*
G01Y-40054D02*
X998943Y-38596D01*
X1000253Y-37429D01*
X1001999Y-37138D01*
X1003527Y-37429D01*
X1004838Y-38596D01*
X1005493Y-40637D01*
Y-48804D01*
G01X1016006Y-40929D02*
X1022993D01*
X1022338Y-38887D01*
X1021246Y-37721D01*
X1019718Y-37138D01*
X1018189Y-37429D01*
X1016879Y-38304D01*
X1016006Y-40346D01*
X1015569Y-42096D01*
Y-43846D01*
X1016006Y-45596D01*
X1017098Y-47346D01*
X1018408Y-48512D01*
X1019936Y-48804D01*
X1021464Y-48221D01*
X1022993Y-46471D01*
G01X1033724Y-48804D02*
Y-37138D01*
G01Y-39471D02*
X1034816Y-38304D01*
X1035908Y-37429D01*
X1037436Y-37138D01*
X1038527Y-37429D01*
X1039838Y-38304D01*
G01X1080481Y-76304D02*
X1078734Y-76887D01*
X1077424Y-78346D01*
X1076551Y-80095D01*
X1075896Y-82429D01*
X1075678Y-85054D01*
X1075896Y-87679D01*
X1076551Y-90013D01*
X1077424Y-91763D01*
X1078734Y-93221D01*
X1080481Y-93804D01*
X1082227Y-93221D01*
X1083538Y-91763D01*
X1084411Y-90013D01*
X1085066Y-87679D01*
X1085284Y-85054D01*
X1085066Y-82429D01*
X1084411Y-80095D01*
X1083538Y-78346D01*
X1082227Y-76887D01*
X1080481Y-76304D01*
G01X1097981Y-93804D02*
X1099509Y-93512D01*
X1101256Y-92638D01*
X1102348Y-91180D01*
X1102784Y-89137D01*
X1102348Y-87096D01*
X1101038Y-85346D01*
X1099073Y-84471D01*
X1096889D01*
X1095579Y-83887D01*
X1094487Y-82429D01*
X1094051Y-80388D01*
X1094706Y-78346D01*
X1096234Y-76887D01*
X1097981Y-76304D01*
X1099727Y-76887D01*
X1101256Y-78346D01*
X1101911Y-80388D01*
X1101474Y-82429D01*
X1100383Y-83887D01*
X1099073Y-84471D01*
X1096889D01*
X1094924Y-85346D01*
X1093614Y-87096D01*
X1093178Y-89137D01*
X1093614Y-91180D01*
X1094706Y-92638D01*
X1096453Y-93512D01*
X1097981Y-93804D01*
G01X1111551Y-94387D02*
X1119411Y-76304D01*
G01X1132981D02*
X1131234Y-76887D01*
X1129924Y-78346D01*
X1129051Y-80095D01*
X1128396Y-82429D01*
X1128178Y-85054D01*
X1128396Y-87679D01*
X1129051Y-90013D01*
X1129924Y-91763D01*
X1131234Y-93221D01*
X1132981Y-93804D01*
X1134727Y-93221D01*
X1136038Y-91763D01*
X1136911Y-90013D01*
X1137566Y-87679D01*
X1137784Y-85054D01*
X1137566Y-82429D01*
X1136911Y-80095D01*
X1136038Y-78346D01*
X1134727Y-76887D01*
X1132981Y-76304D01*
G01X1150044Y-93804D02*
X1150481Y-90013D01*
X1151136Y-86804D01*
X1152009Y-83887D01*
X1153101Y-80679D01*
X1154848Y-76304D01*
X1146114D01*
G01X1164051Y-94387D02*
X1171911Y-76304D01*
G01X1181333Y-79221D02*
X1182643Y-77471D01*
X1184171Y-76596D01*
X1185918Y-76304D01*
X1188101Y-76887D01*
X1189629Y-78346D01*
X1190066Y-80095D01*
X1189848Y-81846D01*
X1188974Y-83304D01*
X1184608Y-86221D01*
X1182643Y-88262D01*
X1181333Y-91180D01*
X1180896Y-93804D01*
X1190066D01*
G01X1202981Y-76304D02*
X1201234Y-76887D01*
X1199924Y-78346D01*
X1199051Y-80095D01*
X1198396Y-82429D01*
X1198178Y-85054D01*
X1198396Y-87679D01*
X1199051Y-90013D01*
X1199924Y-91763D01*
X1201234Y-93221D01*
X1202981Y-93804D01*
X1204727Y-93221D01*
X1206038Y-91763D01*
X1206911Y-90013D01*
X1207566Y-87679D01*
X1207784Y-85054D01*
X1207566Y-82429D01*
X1206911Y-80095D01*
X1206038Y-78346D01*
X1204727Y-76887D01*
X1202981Y-76304D01*
G01X1220481Y-93804D02*
Y-76304D01*
X1217861Y-79804D01*
G01Y-93804D02*
X1223101D01*
G01X1237544D02*
X1237981Y-90013D01*
X1238636Y-86804D01*
X1239509Y-83887D01*
X1240601Y-80679D01*
X1242348Y-76304D01*
X1233614D01*
G01X1128178Y-48804D02*
Y-31304D01*
X1132544D01*
X1134291Y-32179D01*
X1135601Y-33346D01*
X1136693Y-35095D01*
X1137566Y-37138D01*
X1137784Y-40054D01*
X1137566Y-42971D01*
X1136693Y-45013D01*
X1135601Y-46763D01*
X1134291Y-47929D01*
X1132544Y-48804D01*
X1128178D01*
G01X1154411D02*
Y-37138D01*
G01Y-39179D02*
X1153538Y-38013D01*
X1152227Y-37429D01*
X1150699Y-37138D01*
X1149171Y-37721D01*
X1147861Y-38887D01*
X1146987Y-40637D01*
X1146551Y-42971D01*
X1146987Y-45304D01*
X1147861Y-47054D01*
X1149171Y-48221D01*
X1150699Y-48804D01*
X1152227Y-48512D01*
X1153538Y-47638D01*
X1154411Y-46471D01*
G01X1167981Y-31304D02*
Y-48804D01*
G01X1164924Y-37138D02*
X1171038D01*
G01X1182206Y-40929D02*
X1189193D01*
X1188538Y-38887D01*
X1187446Y-37721D01*
X1185918Y-37138D01*
X1184389Y-37429D01*
X1183079Y-38304D01*
X1182206Y-40346D01*
X1181769Y-42096D01*
Y-43846D01*
X1182206Y-45596D01*
X1183298Y-47346D01*
X1184608Y-48512D01*
X1186136Y-48804D01*
X1187664Y-48221D01*
X1189193Y-46471D01*
M02*
